FILE_TYPE = MACRO_DRAWING;
SET COLOR_WIRE YELLOW;
SET COLOR_PROP ORANGE;
SET COLOR_DOT WHITE;
SET COLOR_ARC YELLOW;
SET COLOR_BODY GREEN;
SET COLOR_NOTE PURPLE;
SET PROP_DISPLAY VALUE;
SET PAGE_NUMBER P49;
FORCEADD GENOA_SP5..11
(-4775 5000);
FORCEPROP 1 LAST LOCATION U26
J 0
(-5870 6256);
DISPLAY 0.489362 (-5870 6256);
PAINT SKYBLUE (-5870 6256);
FORCEPROP 0 LAST $SEC 11
J 0
(-5850 6300);
DISPLAY 0.680851 (-5850 6300);
PAINT MONO (-5850 6300);
DISPLAY INVISIBLE (-5850 6300);
FORCEPROP 0 LAST CDS_SEC 11
J 0
(-5875 6225);
DISPLAY 1.021277 (-5875 6225);
DISPLAY INVISIBLE (-5875 6225);
FORCEPROP 0 LASTPIN (-6025 5700) $PN M40
J 2
(-6035 5710);
DISPLAY 0.489362 (-6035 5710);
PAINT MONO (-6035 5710);
FORCEPROP 0 LASTPIN (-6025 5600) $PN K40
J 2
(-6035 5610);
DISPLAY 0.489362 (-6035 5610);
PAINT MONO (-6035 5610);
FORCEPROP 0 LASTPIN (-6025 5500) $PN H40
J 2
(-6035 5510);
DISPLAY 0.489362 (-6035 5510);
PAINT MONO (-6035 5510);
FORCEPROP 0 LASTPIN (-6025 5400) $PN L43
J 2
(-6035 5410);
DISPLAY 0.489362 (-6035 5410);
PAINT MONO (-6035 5410);
FORCEPROP 0 LASTPIN (-6025 5300) $PN G43
J 2
(-6035 5310);
DISPLAY 0.489362 (-6035 5310);
PAINT MONO (-6035 5310);
FORCEPROP 0 LASTPIN (-6025 5200) $PN J43
J 2
(-6035 5210);
DISPLAY 0.489362 (-6035 5210);
PAINT MONO (-6035 5210);
FORCEPROP 0 LASTPIN (-6025 5100) $PN L46
J 2
(-6035 5110);
DISPLAY 0.489362 (-6035 5110);
PAINT MONO (-6035 5110);
FORCEPROP 0 LASTPIN (-6025 5000) $PN G46
J 2
(-6035 5010);
DISPLAY 0.489362 (-6035 5010);
PAINT MONO (-6035 5010);
FORCEPROP 0 LASTPIN (-6025 4900) $PN J46
J 2
(-6035 4910);
DISPLAY 0.489362 (-6035 4910);
PAINT MONO (-6035 4910);
FORCEPROP 0 LASTPIN (-6025 4800) $PN L49
J 2
(-6035 4810);
DISPLAY 0.489362 (-6035 4810);
PAINT MONO (-6035 4810);
FORCEPROP 0 LASTPIN (-6025 4700) $PN G49
J 2
(-6035 4710);
DISPLAY 0.489362 (-6035 4710);
PAINT MONO (-6035 4710);
FORCEPROP 0 LASTPIN (-6025 4600) $PN J49
J 2
(-6035 4610);
DISPLAY 0.489362 (-6035 4610);
PAINT MONO (-6035 4610);
FORCEPROP 0 LASTPIN (-6025 4500) $PN L52
J 2
(-6035 4510);
DISPLAY 0.489362 (-6035 4510);
PAINT MONO (-6035 4510);
FORCEPROP 0 LASTPIN (-6025 4400) $PN G52
J 2
(-6035 4410);
DISPLAY 0.489362 (-6035 4410);
PAINT MONO (-6035 4410);
FORCEPROP 0 LASTPIN (-6025 4300) $PN J52
J 2
(-6035 4310);
DISPLAY 0.489362 (-6035 4310);
PAINT MONO (-6035 4310);
FORCEPROP 0 LASTPIN (-6025 4200) $PN N52
J 2
(-6035 4210);
DISPLAY 0.489362 (-6035 4210);
PAINT MONO (-6035 4210);
FORCEPROP 0 LASTPIN (-6025 5750) $PN M41
J 2
(-6035 5760);
DISPLAY 0.489362 (-6035 5760);
PAINT MONO (-6035 5760);
FORCEPROP 0 LASTPIN (-6025 5650) $PN K41
J 2
(-6035 5660);
DISPLAY 0.489362 (-6035 5660);
PAINT MONO (-6035 5660);
FORCEPROP 0 LASTPIN (-6025 5550) $PN H41
J 2
(-6035 5560);
DISPLAY 0.489362 (-6035 5560);
PAINT MONO (-6035 5560);
FORCEPROP 0 LASTPIN (-6025 5450) $PN L44
J 2
(-6035 5460);
DISPLAY 0.489362 (-6035 5460);
PAINT MONO (-6035 5460);
FORCEPROP 0 LASTPIN (-6025 5350) $PN G44
J 2
(-6035 5360);
DISPLAY 0.489362 (-6035 5360);
PAINT MONO (-6035 5360);
FORCEPROP 0 LASTPIN (-6025 5250) $PN J44
J 2
(-6035 5260);
DISPLAY 0.489362 (-6035 5260);
PAINT MONO (-6035 5260);
FORCEPROP 0 LASTPIN (-6025 5150) $PN L47
J 2
(-6035 5160);
DISPLAY 0.489362 (-6035 5160);
PAINT MONO (-6035 5160);
FORCEPROP 0 LASTPIN (-6025 5050) $PN G47
J 2
(-6035 5060);
DISPLAY 0.489362 (-6035 5060);
PAINT MONO (-6035 5060);
FORCEPROP 0 LASTPIN (-6025 4950) $PN J47
J 2
(-6035 4960);
DISPLAY 0.489362 (-6035 4960);
PAINT MONO (-6035 4960);
FORCEPROP 0 LASTPIN (-6025 4850) $PN L50
J 2
(-6035 4860);
DISPLAY 0.489362 (-6035 4860);
PAINT MONO (-6035 4860);
FORCEPROP 0 LASTPIN (-6025 4750) $PN G50
J 2
(-6035 4760);
DISPLAY 0.489362 (-6035 4760);
PAINT MONO (-6035 4760);
FORCEPROP 0 LASTPIN (-6025 4650) $PN J50
J 2
(-6035 4660);
DISPLAY 0.489362 (-6035 4660);
PAINT MONO (-6035 4660);
FORCEPROP 0 LASTPIN (-6025 4550) $PN L53
J 2
(-6035 4560);
DISPLAY 0.489362 (-6035 4560);
PAINT MONO (-6035 4560);
FORCEPROP 0 LASTPIN (-6025 4450) $PN G53
J 2
(-6035 4460);
DISPLAY 0.489362 (-6035 4460);
PAINT MONO (-6035 4460);
FORCEPROP 0 LASTPIN (-6025 4350) $PN J53
J 2
(-6035 4360);
DISPLAY 0.489362 (-6035 4360);
PAINT MONO (-6035 4360);
FORCEPROP 0 LASTPIN (-6025 4250) $PN N53
J 2
(-6035 4260);
DISPLAY 0.489362 (-6035 4260);
PAINT MONO (-6035 4260);
FORCEPROP 0 LASTPIN (-3525 5700) $PN AF41
J 0
(-3515 5710);
DISPLAY 0.489362 (-3515 5710);
PAINT MONO (-3515 5710);
FORCEPROP 0 LASTPIN (-3525 5600) $PN AD41
J 0
(-3515 5610);
DISPLAY 0.489362 (-3515 5610);
PAINT MONO (-3515 5610);
FORCEPROP 0 LASTPIN (-3525 5500) $PN AB41
J 0
(-3515 5510);
DISPLAY 0.489362 (-3515 5510);
PAINT MONO (-3515 5510);
FORCEPROP 0 LASTPIN (-3525 5400) $PN AG44
J 0
(-3515 5410);
DISPLAY 0.489362 (-3515 5410);
PAINT MONO (-3515 5410);
FORCEPROP 0 LASTPIN (-3525 5300) $PN AA44
J 0
(-3515 5310);
DISPLAY 0.489362 (-3515 5310);
PAINT MONO (-3515 5310);
FORCEPROP 0 LASTPIN (-3525 5200) $PN AC44
J 0
(-3515 5210);
DISPLAY 0.489362 (-3515 5210);
PAINT MONO (-3515 5210);
FORCEPROP 0 LASTPIN (-3525 5100) $PN AE44
J 0
(-3515 5110);
DISPLAY 0.489362 (-3515 5110);
PAINT MONO (-3515 5110);
FORCEPROP 0 LASTPIN (-3525 5000) $PN AG47
J 0
(-3515 5010);
DISPLAY 0.489362 (-3515 5010);
PAINT MONO (-3515 5010);
FORCEPROP 0 LASTPIN (-3525 4900) $PN AC47
J 0
(-3515 4910);
DISPLAY 0.489362 (-3515 4910);
PAINT MONO (-3515 4910);
FORCEPROP 0 LASTPIN (-3525 4800) $PN AE47
J 0
(-3515 4810);
DISPLAY 0.489362 (-3515 4810);
PAINT MONO (-3515 4810);
FORCEPROP 0 LASTPIN (-3525 4700) $PN AG50
J 0
(-3515 4710);
DISPLAY 0.489362 (-3515 4710);
PAINT MONO (-3515 4710);
FORCEPROP 0 LASTPIN (-3525 4600) $PN AC50
J 0
(-3515 4610);
DISPLAY 0.489362 (-3515 4610);
PAINT MONO (-3515 4610);
FORCEPROP 0 LASTPIN (-3525 4500) $PN AE50
J 0
(-3515 4510);
DISPLAY 0.489362 (-3515 4510);
PAINT MONO (-3515 4510);
FORCEPROP 0 LASTPIN (-3525 4400) $PN AG53
J 0
(-3515 4410);
DISPLAY 0.489362 (-3515 4410);
PAINT MONO (-3515 4410);
FORCEPROP 0 LASTPIN (-3525 4300) $PN AC53
J 0
(-3515 4310);
DISPLAY 0.489362 (-3515 4310);
PAINT MONO (-3515 4310);
FORCEPROP 0 LASTPIN (-3525 4200) $PN AE53
J 0
(-3515 4210);
DISPLAY 0.489362 (-3515 4210);
PAINT MONO (-3515 4210);
FORCEPROP 0 LASTPIN (-3525 5750) $PN AF40
J 0
(-3515 5760);
DISPLAY 0.489362 (-3515 5760);
PAINT MONO (-3515 5760);
FORCEPROP 0 LASTPIN (-3525 5650) $PN AD40
J 0
(-3515 5660);
DISPLAY 0.489362 (-3515 5660);
PAINT MONO (-3515 5660);
FORCEPROP 0 LASTPIN (-3525 5550) $PN AB40
J 0
(-3515 5560);
DISPLAY 0.489362 (-3515 5560);
PAINT MONO (-3515 5560);
FORCEPROP 0 LASTPIN (-3525 5450) $PN AG43
J 0
(-3515 5460);
DISPLAY 0.489362 (-3515 5460);
PAINT MONO (-3515 5460);
FORCEPROP 0 LASTPIN (-3525 5350) $PN AA43
J 0
(-3515 5360);
DISPLAY 0.489362 (-3515 5360);
PAINT MONO (-3515 5360);
FORCEPROP 0 LASTPIN (-3525 5250) $PN AC43
J 0
(-3515 5260);
DISPLAY 0.489362 (-3515 5260);
PAINT MONO (-3515 5260);
FORCEPROP 0 LASTPIN (-3525 5150) $PN AE43
J 0
(-3515 5160);
DISPLAY 0.489362 (-3515 5160);
PAINT MONO (-3515 5160);
FORCEPROP 0 LASTPIN (-3525 5050) $PN AG46
J 0
(-3515 5060);
DISPLAY 0.489362 (-3515 5060);
PAINT MONO (-3515 5060);
FORCEPROP 0 LASTPIN (-3525 4950) $PN AC46
J 0
(-3515 4960);
DISPLAY 0.489362 (-3515 4960);
PAINT MONO (-3515 4960);
FORCEPROP 0 LASTPIN (-3525 4850) $PN AE46
J 0
(-3515 4860);
DISPLAY 0.489362 (-3515 4860);
PAINT MONO (-3515 4860);
FORCEPROP 0 LASTPIN (-3525 4750) $PN AG49
J 0
(-3515 4760);
DISPLAY 0.489362 (-3515 4760);
PAINT MONO (-3515 4760);
FORCEPROP 0 LASTPIN (-3525 4650) $PN AC49
J 0
(-3515 4660);
DISPLAY 0.489362 (-3515 4660);
PAINT MONO (-3515 4660);
FORCEPROP 0 LASTPIN (-3525 4550) $PN AE49
J 0
(-3515 4560);
DISPLAY 0.489362 (-3515 4560);
PAINT MONO (-3515 4560);
FORCEPROP 0 LASTPIN (-3525 4450) $PN AG52
J 0
(-3515 4460);
DISPLAY 0.489362 (-3515 4460);
PAINT MONO (-3515 4460);
FORCEPROP 0 LASTPIN (-3525 4350) $PN AC52
J 0
(-3515 4360);
DISPLAY 0.489362 (-3515 4360);
PAINT MONO (-3515 4360);
FORCEPROP 0 LASTPIN (-3525 4250) $PN AE52
J 0
(-3515 4260);
DISPLAY 0.489362 (-3515 4260);
PAINT MONO (-3515 4260);
FORCEPROP 2 LAST VALUE SOCKET6096_13568-001
J 0
(-5875 6075);
DISPLAY 0.489362 (-5875 6075);
PAINT SKYBLUE (-5875 6075);
FORCEPROP 1 LAST MATERIAL IO
J 0
(-5870 5982);
DISPLAY 0.489362 (-5870 5982);
PAINT SKYBLUE (-5870 5982);
FORCEPROP 2 LAST PART_TYPE SMLF
J 0
(-5875 6175);
DISPLAY 1.021277 (-5875 6175);
FORCEPROP 1 LAST CDS_LMAN_SYM_OUTLINE -1100,950,1100,-950
J 0
(-4775 5000);
DISPLAY 0.468085 (-4775 5000);
PAINT GREEN (-4775 5000);
DISPLAY INVISIBLE (-4775 5000);
FORCEPROP 1 LAST NEEDS_NO_SIZE TRUE
J 0
(-4775 5000);
DISPLAY 0.723404 (-4775 5000);
PAINT GREEN (-4775 5000);
DISPLAY INVISIBLE (-4775 5000);
FORCEPROP 2 LAST CDS_LIB pure_quanta
J 0
(-4775 5000);
DISPLAY INVISIBLE (-4775 5000);
FORCEPROP 1 LAST PATH I213
J 0
(-4775 5000);
DISPLAY 0.723404 (-4775 5000);
PAINT GREEN (-4775 5000);
DISPLAY INVISIBLE (-4775 5000);
FORCEPROP 1 LAST PART_NUMBER DGA^6000030
J 0
(-5870 6109);
DISPLAY 0.489362 (-5870 6109);
PAINT SKYBLUE (-5870 6109);
DISPLAY INVISIBLE (-5870 6109);
FORCEADD GENOA_SP5..12
(-4750 2275);
FORCEPROP 1 LAST LOCATION U26
J 0
(-5845 3531);
DISPLAY 0.489362 (-5845 3531);
PAINT SKYBLUE (-5845 3531);
FORCEPROP 0 LAST $SEC 12
J 0
(-5825 3575);
DISPLAY 0.680851 (-5825 3575);
PAINT MONO (-5825 3575);
DISPLAY INVISIBLE (-5825 3575);
FORCEPROP 0 LAST CDS_SEC 12
J 0
(-5850 3500);
DISPLAY 1.021277 (-5850 3500);
DISPLAY INVISIBLE (-5850 3500);
FORCEPROP 0 LASTPIN (-6000 2975) $PN V40
J 2
(-6010 2985);
DISPLAY 0.489362 (-6010 2985);
PAINT MONO (-6010 2985);
FORCEPROP 0 LASTPIN (-6000 2875) $PN T40
J 2
(-6010 2885);
DISPLAY 0.489362 (-6010 2885);
PAINT MONO (-6010 2885);
FORCEPROP 0 LASTPIN (-6000 2775) $PN P40
J 2
(-6010 2785);
DISPLAY 0.489362 (-6010 2785);
PAINT MONO (-6010 2785);
FORCEPROP 0 LASTPIN (-6000 2675) $PN U43
J 2
(-6010 2685);
DISPLAY 0.489362 (-6010 2685);
PAINT MONO (-6010 2685);
FORCEPROP 0 LASTPIN (-6000 2575) $PN N43
J 2
(-6010 2585);
DISPLAY 0.489362 (-6010 2585);
PAINT MONO (-6010 2585);
FORCEPROP 0 LASTPIN (-6000 2475) $PN R43
J 2
(-6010 2485);
DISPLAY 0.489362 (-6010 2485);
PAINT MONO (-6010 2485);
FORCEPROP 0 LASTPIN (-6000 2375) $PN U46
J 2
(-6010 2385);
DISPLAY 0.489362 (-6010 2385);
PAINT MONO (-6010 2385);
FORCEPROP 0 LASTPIN (-6000 2275) $PN N46
J 2
(-6010 2285);
DISPLAY 0.489362 (-6010 2285);
PAINT MONO (-6010 2285);
FORCEPROP 0 LASTPIN (-6000 2175) $PN R46
J 2
(-6010 2185);
DISPLAY 0.489362 (-6010 2185);
PAINT MONO (-6010 2185);
FORCEPROP 0 LASTPIN (-6000 2075) $PN W49
J 2
(-6010 2085);
DISPLAY 0.489362 (-6010 2085);
PAINT MONO (-6010 2085);
FORCEPROP 0 LASTPIN (-6000 1975) $PN N49
J 2
(-6010 1985);
DISPLAY 0.489362 (-6010 1985);
PAINT MONO (-6010 1985);
FORCEPROP 0 LASTPIN (-6000 1875) $PN R49
J 2
(-6010 1885);
DISPLAY 0.489362 (-6010 1885);
PAINT MONO (-6010 1885);
FORCEPROP 0 LASTPIN (-6000 1775) $PN U49
J 2
(-6010 1785);
DISPLAY 0.489362 (-6010 1785);
PAINT MONO (-6010 1785);
FORCEPROP 0 LASTPIN (-6000 1675) $PN W52
J 2
(-6010 1685);
DISPLAY 0.489362 (-6010 1685);
PAINT MONO (-6010 1685);
FORCEPROP 0 LASTPIN (-6000 1575) $PN R52
J 2
(-6010 1585);
DISPLAY 0.489362 (-6010 1585);
PAINT MONO (-6010 1585);
FORCEPROP 0 LASTPIN (-6000 1475) $PN U52
J 2
(-6010 1485);
DISPLAY 0.489362 (-6010 1485);
PAINT MONO (-6010 1485);
FORCEPROP 0 LASTPIN (-6000 3025) $PN V41
J 2
(-6010 3035);
DISPLAY 0.489362 (-6010 3035);
PAINT MONO (-6010 3035);
FORCEPROP 0 LASTPIN (-6000 2925) $PN T41
J 2
(-6010 2935);
DISPLAY 0.489362 (-6010 2935);
PAINT MONO (-6010 2935);
FORCEPROP 0 LASTPIN (-6000 2825) $PN P41
J 2
(-6010 2835);
DISPLAY 0.489362 (-6010 2835);
PAINT MONO (-6010 2835);
FORCEPROP 0 LASTPIN (-6000 2725) $PN U44
J 2
(-6010 2735);
DISPLAY 0.489362 (-6010 2735);
PAINT MONO (-6010 2735);
FORCEPROP 0 LASTPIN (-6000 2625) $PN N44
J 2
(-6010 2635);
DISPLAY 0.489362 (-6010 2635);
PAINT MONO (-6010 2635);
FORCEPROP 0 LASTPIN (-6000 2525) $PN R44
J 2
(-6010 2535);
DISPLAY 0.489362 (-6010 2535);
PAINT MONO (-6010 2535);
FORCEPROP 0 LASTPIN (-6000 2425) $PN U47
J 2
(-6010 2435);
DISPLAY 0.489362 (-6010 2435);
PAINT MONO (-6010 2435);
FORCEPROP 0 LASTPIN (-6000 2325) $PN N47
J 2
(-6010 2335);
DISPLAY 0.489362 (-6010 2335);
PAINT MONO (-6010 2335);
FORCEPROP 0 LASTPIN (-6000 2225) $PN R47
J 2
(-6010 2235);
DISPLAY 0.489362 (-6010 2235);
PAINT MONO (-6010 2235);
FORCEPROP 0 LASTPIN (-6000 2125) $PN W50
J 2
(-6010 2135);
DISPLAY 0.489362 (-6010 2135);
PAINT MONO (-6010 2135);
FORCEPROP 0 LASTPIN (-6000 2025) $PN N50
J 2
(-6010 2035);
DISPLAY 0.489362 (-6010 2035);
PAINT MONO (-6010 2035);
FORCEPROP 0 LASTPIN (-6000 1925) $PN R50
J 2
(-6010 1935);
DISPLAY 0.489362 (-6010 1935);
PAINT MONO (-6010 1935);
FORCEPROP 0 LASTPIN (-6000 1825) $PN U50
J 2
(-6010 1835);
DISPLAY 0.489362 (-6010 1835);
PAINT MONO (-6010 1835);
FORCEPROP 0 LASTPIN (-6000 1725) $PN W53
J 2
(-6010 1735);
DISPLAY 0.489362 (-6010 1735);
PAINT MONO (-6010 1735);
FORCEPROP 0 LASTPIN (-6000 1625) $PN R53
J 2
(-6010 1635);
DISPLAY 0.489362 (-6010 1635);
PAINT MONO (-6010 1635);
FORCEPROP 0 LASTPIN (-6000 1525) $PN U53
J 2
(-6010 1535);
DISPLAY 0.489362 (-6010 1535);
PAINT MONO (-6010 1535);
FORCEPROP 0 LASTPIN (-3500 2975) $PN AP41
J 0
(-3490 2985);
DISPLAY 0.489362 (-3490 2985);
PAINT MONO (-3490 2985);
FORCEPROP 0 LASTPIN (-3500 2875) $PN AM41
J 0
(-3490 2885);
DISPLAY 0.489362 (-3490 2885);
PAINT MONO (-3490 2885);
FORCEPROP 0 LASTPIN (-3500 2775) $PN AH41
J 0
(-3490 2785);
DISPLAY 0.489362 (-3490 2785);
PAINT MONO (-3490 2785);
FORCEPROP 0 LASTPIN (-3500 2675) $PN AK41
J 0
(-3490 2685);
DISPLAY 0.489362 (-3490 2685);
PAINT MONO (-3490 2685);
FORCEPROP 0 LASTPIN (-3500 2575) $PN AN44
J 0
(-3490 2585);
DISPLAY 0.489362 (-3490 2585);
PAINT MONO (-3490 2585);
FORCEPROP 0 LASTPIN (-3500 2475) $PN AJ44
J 0
(-3490 2485);
DISPLAY 0.489362 (-3490 2485);
PAINT MONO (-3490 2485);
FORCEPROP 0 LASTPIN (-3500 2375) $PN AL44
J 0
(-3490 2385);
DISPLAY 0.489362 (-3490 2385);
PAINT MONO (-3490 2385);
FORCEPROP 0 LASTPIN (-3500 2275) $PN AN47
J 0
(-3490 2285);
DISPLAY 0.489362 (-3490 2285);
PAINT MONO (-3490 2285);
FORCEPROP 0 LASTPIN (-3500 2175) $PN AJ47
J 0
(-3490 2185);
DISPLAY 0.489362 (-3490 2185);
PAINT MONO (-3490 2185);
FORCEPROP 0 LASTPIN (-3500 2075) $PN AL47
J 0
(-3490 2085);
DISPLAY 0.489362 (-3490 2085);
PAINT MONO (-3490 2085);
FORCEPROP 0 LASTPIN (-3500 1975) $PN AN50
J 0
(-3490 1985);
DISPLAY 0.489362 (-3490 1985);
PAINT MONO (-3490 1985);
FORCEPROP 0 LASTPIN (-3500 1875) $PN AJ50
J 0
(-3490 1885);
DISPLAY 0.489362 (-3490 1885);
PAINT MONO (-3490 1885);
FORCEPROP 0 LASTPIN (-3500 1775) $PN AL50
J 0
(-3490 1785);
DISPLAY 0.489362 (-3490 1785);
PAINT MONO (-3490 1785);
FORCEPROP 0 LASTPIN (-3500 1675) $PN AN53
J 0
(-3490 1685);
DISPLAY 0.489362 (-3490 1685);
PAINT MONO (-3490 1685);
FORCEPROP 0 LASTPIN (-3500 1575) $PN AJ53
J 0
(-3490 1585);
DISPLAY 0.489362 (-3490 1585);
PAINT MONO (-3490 1585);
FORCEPROP 0 LASTPIN (-3500 1475) $PN AL53
J 0
(-3490 1485);
DISPLAY 0.489362 (-3490 1485);
PAINT MONO (-3490 1485);
FORCEPROP 0 LASTPIN (-3500 3025) $PN AP40
J 0
(-3490 3035);
DISPLAY 0.489362 (-3490 3035);
PAINT MONO (-3490 3035);
FORCEPROP 0 LASTPIN (-3500 2925) $PN AM40
J 0
(-3490 2935);
DISPLAY 0.489362 (-3490 2935);
PAINT MONO (-3490 2935);
FORCEPROP 0 LASTPIN (-3500 2825) $PN AH40
J 0
(-3490 2835);
DISPLAY 0.489362 (-3490 2835);
PAINT MONO (-3490 2835);
FORCEPROP 0 LASTPIN (-3500 2725) $PN AK40
J 0
(-3490 2735);
DISPLAY 0.489362 (-3490 2735);
PAINT MONO (-3490 2735);
FORCEPROP 0 LASTPIN (-3500 2625) $PN AN43
J 0
(-3490 2635);
DISPLAY 0.489362 (-3490 2635);
PAINT MONO (-3490 2635);
FORCEPROP 0 LASTPIN (-3500 2525) $PN AJ43
J 0
(-3490 2535);
DISPLAY 0.489362 (-3490 2535);
PAINT MONO (-3490 2535);
FORCEPROP 0 LASTPIN (-3500 2425) $PN AL43
J 0
(-3490 2435);
DISPLAY 0.489362 (-3490 2435);
PAINT MONO (-3490 2435);
FORCEPROP 0 LASTPIN (-3500 2325) $PN AN46
J 0
(-3490 2335);
DISPLAY 0.489362 (-3490 2335);
PAINT MONO (-3490 2335);
FORCEPROP 0 LASTPIN (-3500 2225) $PN AJ46
J 0
(-3490 2235);
DISPLAY 0.489362 (-3490 2235);
PAINT MONO (-3490 2235);
FORCEPROP 0 LASTPIN (-3500 2125) $PN AL46
J 0
(-3490 2135);
DISPLAY 0.489362 (-3490 2135);
PAINT MONO (-3490 2135);
FORCEPROP 0 LASTPIN (-3500 2025) $PN AN49
J 0
(-3490 2035);
DISPLAY 0.489362 (-3490 2035);
PAINT MONO (-3490 2035);
FORCEPROP 0 LASTPIN (-3500 1925) $PN AJ49
J 0
(-3490 1935);
DISPLAY 0.489362 (-3490 1935);
PAINT MONO (-3490 1935);
FORCEPROP 0 LASTPIN (-3500 1825) $PN AL49
J 0
(-3490 1835);
DISPLAY 0.489362 (-3490 1835);
PAINT MONO (-3490 1835);
FORCEPROP 0 LASTPIN (-3500 1725) $PN AN52
J 0
(-3490 1735);
DISPLAY 0.489362 (-3490 1735);
PAINT MONO (-3490 1735);
FORCEPROP 0 LASTPIN (-3500 1625) $PN AJ52
J 0
(-3490 1635);
DISPLAY 0.489362 (-3490 1635);
PAINT MONO (-3490 1635);
FORCEPROP 0 LASTPIN (-3500 1525) $PN AL52
J 0
(-3490 1535);
DISPLAY 0.489362 (-3490 1535);
PAINT MONO (-3490 1535);
FORCEPROP 1 LAST MATERIAL IO
J 0
(-5845 3257);
DISPLAY 0.489362 (-5845 3257);
PAINT SKYBLUE (-5845 3257);
FORCEPROP 2 LAST VALUE SOCKET6096_13568-001
J 0
(-5850 3328);
DISPLAY 0.489362 (-5850 3328);
PAINT SKYBLUE (-5850 3328);
FORCEPROP 2 LAST PART_TYPE SMLF
J 0
(-5850 3428);
DISPLAY 1.021277 (-5850 3428);
FORCEPROP 1 LAST CDS_LMAN_SYM_OUTLINE -1100,950,1100,-950
J 0
(-4750 2275);
DISPLAY 0.468085 (-4750 2275);
PAINT GREEN (-4750 2275);
DISPLAY INVISIBLE (-4750 2275);
FORCEPROP 1 LAST NEEDS_NO_SIZE TRUE
J 0
(-4750 2275);
DISPLAY 0.723404 (-4750 2275);
PAINT GREEN (-4750 2275);
DISPLAY INVISIBLE (-4750 2275);
FORCEPROP 2 LAST CDS_LIB pure_quanta
J 0
(-4750 2275);
DISPLAY INVISIBLE (-4750 2275);
FORCEPROP 1 LAST PATH I214
J 0
(-4750 2275);
DISPLAY 0.723404 (-4750 2275);
PAINT GREEN (-4750 2275);
DISPLAY INVISIBLE (-4750 2275);
FORCEPROP 1 LAST PART_NUMBER DGA^6000030
J 0
(-5845 3384);
DISPLAY 0.489362 (-5845 3384);
PAINT SKYBLUE (-5845 3384);
DISPLAY INVISIBLE (-5845 3384);
FORCEADD OFFPAGE..2
(-1825 5975);
FORCEPROP 2 LAST $XR0 23 
J 0
(-1636 5975);
DISPLAY 0.638298 (-1636 5975);
PAINT MONO (-1636 5975);
FORCEPROP 2 LAST CDS_LIB standard
J 0
(-1825 5975);
DISPLAY INVISIBLE (-1825 5975);
FORCEPROP 1 LAST OFFPAGE TRUE
J 0
(-1500 5850);
DISPLAY 0.872340 (-1500 5850);
PAINT GREEN (-1500 5850);
DISPLAY INVISIBLE (-1500 5850);
FORCEPROP 1 LAST COMMENT_BODY TRUE
J 0
(-1870 5880);
DISPLAY 0.872340 (-1870 5880);
PAINT GREEN (-1870 5880);
DISPLAY INVISIBLE (-1870 5880);
FORCEPROP 2 LAST PATH I232
J 0
(-1625 6025);
DISPLAY 1.021277 (-1625 6025);
DISPLAY INVISIBLE (-1625 6025);
FORCEADD TAP..6
R 2
(-3100 5650);
FORCEPROP 3 LASTPIN (-3150 5650) SIG_NAME GMI_CPU1_G0_CPU0_G2_TX_DP<14>
J 0
(-3140 5660);
DISPLAY 0.659574 (-3140 5660);
PAINT MONO (-3140 5660);
DISPLAY INVISIBLE (-3140 5660);
FORCEPROP 1 LASTPIN (-3150 5650) BN 14
J 2
(-3098 5658);
DISPLAY 0.489362 (-3098 5658);
PAINT MONO (-3098 5658);
FORCEPROP 2 LAST ROOM RISER1
J 0
(-3600 5700);
DISPLAY 0.829787 (-3600 5700);
PAINT RED (-3600 5700);
DISPLAY INVISIBLE (-3600 5700);
FORCEPROP 2 LAST CDS_LIB mstr_standard
J 0
(-3100 5650);
DISPLAY INVISIBLE (-3100 5650);
FORCEPROP 2 LAST BOM_COST IO_SLOT
J 0
(-3600 5750);
DISPLAY 0.829787 (-3600 5750);
DISPLAY INVISIBLE (-3600 5750);
FORCEPROP 1 LAST BODY_TYPE PLUMBING
J 2
(-3100 5600);
DISPLAY 0.702128 (-3100 5600);
PAINT GREEN (-3100 5600);
DISPLAY INVISIBLE (-3100 5600);
FORCEPROP 1 LAST HDL_TAP TRUE
J 2
(-3425 5525);
DISPLAY 0.702128 (-3425 5525);
PAINT GREEN (-3425 5525);
DISPLAY INVISIBLE (-3425 5525);
FORCEPROP 1 LAST PATH I235
J 2
(-3098 5650);
DISPLAY 0.872340 (-3098 5650);
PAINT GREEN (-3098 5650);
DISPLAY INVISIBLE (-3098 5650);
FORCEADD TAP..6
R 2
(-3100 5750);
FORCEPROP 3 LASTPIN (-3150 5750) SIG_NAME GMI_CPU1_G0_CPU0_G2_TX_DP<15>
J 0
(-3140 5760);
DISPLAY 0.659574 (-3140 5760);
PAINT MONO (-3140 5760);
DISPLAY INVISIBLE (-3140 5760);
FORCEPROP 1 LASTPIN (-3150 5750) BN 15
J 2
(-3098 5758);
DISPLAY 0.489362 (-3098 5758);
PAINT MONO (-3098 5758);
FORCEPROP 2 LAST ROOM RISER1
J 0
(-3600 5800);
DISPLAY 0.829787 (-3600 5800);
PAINT RED (-3600 5800);
DISPLAY INVISIBLE (-3600 5800);
FORCEPROP 2 LAST CDS_LIB mstr_standard
J 0
(-3100 5750);
DISPLAY INVISIBLE (-3100 5750);
FORCEPROP 2 LAST BOM_COST IO_SLOT
J 0
(-3600 5850);
DISPLAY 0.829787 (-3600 5850);
DISPLAY INVISIBLE (-3600 5850);
FORCEPROP 1 LAST BODY_TYPE PLUMBING
J 2
(-3100 5700);
DISPLAY 0.702128 (-3100 5700);
PAINT GREEN (-3100 5700);
DISPLAY INVISIBLE (-3100 5700);
FORCEPROP 1 LAST HDL_TAP TRUE
J 2
(-3425 5625);
DISPLAY 0.702128 (-3425 5625);
PAINT GREEN (-3425 5625);
DISPLAY INVISIBLE (-3425 5625);
FORCEPROP 1 LAST PATH I236
J 2
(-3098 5750);
DISPLAY 0.872340 (-3098 5750);
PAINT GREEN (-3098 5750);
DISPLAY INVISIBLE (-3098 5750);
FORCEADD TAP..6
R 2
(-3100 5550);
FORCEPROP 3 LASTPIN (-3150 5550) SIG_NAME GMI_CPU1_G0_CPU0_G2_TX_DP<13>
J 0
(-3140 5560);
DISPLAY 0.659574 (-3140 5560);
PAINT MONO (-3140 5560);
DISPLAY INVISIBLE (-3140 5560);
FORCEPROP 1 LASTPIN (-3150 5550) BN 13
J 2
(-3098 5558);
DISPLAY 0.489362 (-3098 5558);
PAINT MONO (-3098 5558);
FORCEPROP 2 LAST ROOM RISER1
J 0
(-3600 5600);
DISPLAY 0.829787 (-3600 5600);
PAINT RED (-3600 5600);
DISPLAY INVISIBLE (-3600 5600);
FORCEPROP 2 LAST CDS_LIB standard
J 0
(-3100 5550);
DISPLAY INVISIBLE (-3100 5550);
FORCEPROP 2 LAST BOM_COST IO_SLOT
J 0
(-3600 5650);
DISPLAY 0.829787 (-3600 5650);
DISPLAY INVISIBLE (-3600 5650);
FORCEPROP 1 LAST BODY_TYPE PLUMBING
J 2
(-3100 5500);
DISPLAY 0.702128 (-3100 5500);
PAINT GREEN (-3100 5500);
DISPLAY INVISIBLE (-3100 5500);
FORCEPROP 1 LAST HDL_TAP TRUE
J 2
(-3425 5425);
DISPLAY 0.702128 (-3425 5425);
PAINT GREEN (-3425 5425);
DISPLAY INVISIBLE (-3425 5425);
FORCEPROP 1 LAST PATH I240
J 2
(-3098 5550);
DISPLAY 0.872340 (-3098 5550);
PAINT GREEN (-3098 5550);
DISPLAY INVISIBLE (-3098 5550);
FORCEADD TAP..6
R 2
(-3100 5450);
FORCEPROP 3 LASTPIN (-3150 5450) SIG_NAME GMI_CPU1_G0_CPU0_G2_TX_DP<12>
J 0
(-3140 5460);
DISPLAY 0.659574 (-3140 5460);
PAINT MONO (-3140 5460);
DISPLAY INVISIBLE (-3140 5460);
FORCEPROP 1 LASTPIN (-3150 5450) BN 12
J 2
(-3098 5458);
DISPLAY 0.489362 (-3098 5458);
PAINT MONO (-3098 5458);
FORCEPROP 2 LAST ROOM RISER1
J 0
(-3600 5500);
DISPLAY 0.829787 (-3600 5500);
PAINT RED (-3600 5500);
DISPLAY INVISIBLE (-3600 5500);
FORCEPROP 2 LAST CDS_LIB standard
J 0
(-3100 5450);
DISPLAY INVISIBLE (-3100 5450);
FORCEPROP 2 LAST BOM_COST IO_SLOT
J 0
(-3600 5550);
DISPLAY 0.829787 (-3600 5550);
DISPLAY INVISIBLE (-3600 5550);
FORCEPROP 1 LAST BODY_TYPE PLUMBING
J 2
(-3100 5400);
DISPLAY 0.702128 (-3100 5400);
PAINT GREEN (-3100 5400);
DISPLAY INVISIBLE (-3100 5400);
FORCEPROP 1 LAST HDL_TAP TRUE
J 2
(-3425 5325);
DISPLAY 0.702128 (-3425 5325);
PAINT GREEN (-3425 5325);
DISPLAY INVISIBLE (-3425 5325);
FORCEPROP 1 LAST PATH I241
J 2
(-3098 5450);
DISPLAY 0.872340 (-3098 5450);
PAINT GREEN (-3098 5450);
DISPLAY INVISIBLE (-3098 5450);
FORCEADD TAP..6
R 2
(-3100 5350);
FORCEPROP 3 LASTPIN (-3150 5350) SIG_NAME GMI_CPU1_G0_CPU0_G2_TX_DP<11>
J 0
(-3140 5360);
DISPLAY 0.659574 (-3140 5360);
PAINT MONO (-3140 5360);
DISPLAY INVISIBLE (-3140 5360);
FORCEPROP 1 LASTPIN (-3150 5350) BN 11
J 2
(-3098 5358);
DISPLAY 0.489362 (-3098 5358);
PAINT MONO (-3098 5358);
FORCEPROP 2 LAST ROOM RISER1
J 0
(-3600 5400);
DISPLAY 0.829787 (-3600 5400);
PAINT RED (-3600 5400);
DISPLAY INVISIBLE (-3600 5400);
FORCEPROP 2 LAST CDS_LIB standard
J 0
(-3100 5350);
DISPLAY INVISIBLE (-3100 5350);
FORCEPROP 2 LAST BOM_COST IO_SLOT
J 0
(-3600 5450);
DISPLAY 0.829787 (-3600 5450);
DISPLAY INVISIBLE (-3600 5450);
FORCEPROP 1 LAST BODY_TYPE PLUMBING
J 2
(-3100 5300);
DISPLAY 0.702128 (-3100 5300);
PAINT GREEN (-3100 5300);
DISPLAY INVISIBLE (-3100 5300);
FORCEPROP 1 LAST HDL_TAP TRUE
J 2
(-3425 5225);
DISPLAY 0.702128 (-3425 5225);
PAINT GREEN (-3425 5225);
DISPLAY INVISIBLE (-3425 5225);
FORCEPROP 1 LAST PATH I244
J 2
(-3098 5350);
DISPLAY 0.872340 (-3098 5350);
PAINT GREEN (-3098 5350);
DISPLAY INVISIBLE (-3098 5350);
FORCEADD TAP..6
R 2
(-3100 5250);
FORCEPROP 3 LASTPIN (-3150 5250) SIG_NAME GMI_CPU1_G0_CPU0_G2_TX_DP<10>
J 0
(-3140 5260);
DISPLAY 0.659574 (-3140 5260);
PAINT MONO (-3140 5260);
DISPLAY INVISIBLE (-3140 5260);
FORCEPROP 1 LASTPIN (-3150 5250) BN 10
J 2
(-3098 5258);
DISPLAY 0.489362 (-3098 5258);
PAINT MONO (-3098 5258);
FORCEPROP 2 LAST ROOM RISER1
J 0
(-3600 5300);
DISPLAY 0.829787 (-3600 5300);
PAINT RED (-3600 5300);
DISPLAY INVISIBLE (-3600 5300);
FORCEPROP 2 LAST CDS_LIB standard
J 0
(-3100 5250);
DISPLAY INVISIBLE (-3100 5250);
FORCEPROP 2 LAST BOM_COST IO_SLOT
J 0
(-3600 5350);
DISPLAY 0.829787 (-3600 5350);
DISPLAY INVISIBLE (-3600 5350);
FORCEPROP 1 LAST BODY_TYPE PLUMBING
J 2
(-3100 5200);
DISPLAY 0.702128 (-3100 5200);
PAINT GREEN (-3100 5200);
DISPLAY INVISIBLE (-3100 5200);
FORCEPROP 1 LAST HDL_TAP TRUE
J 2
(-3425 5125);
DISPLAY 0.702128 (-3425 5125);
PAINT GREEN (-3425 5125);
DISPLAY INVISIBLE (-3425 5125);
FORCEPROP 1 LAST PATH I245
J 2
(-3098 5250);
DISPLAY 0.872340 (-3098 5250);
PAINT GREEN (-3098 5250);
DISPLAY INVISIBLE (-3098 5250);
FORCEADD TAP..6
R 2
(-3100 5150);
FORCEPROP 3 LASTPIN (-3150 5150) SIG_NAME GMI_CPU1_G0_CPU0_G2_TX_DP<9>
J 0
(-3140 5160);
DISPLAY 0.659574 (-3140 5160);
PAINT MONO (-3140 5160);
DISPLAY INVISIBLE (-3140 5160);
FORCEPROP 1 LASTPIN (-3150 5150) BN 9
J 2
(-3098 5158);
DISPLAY 0.489362 (-3098 5158);
PAINT MONO (-3098 5158);
FORCEPROP 2 LAST ROOM RISER1
J 0
(-3600 5200);
DISPLAY 0.829787 (-3600 5200);
PAINT RED (-3600 5200);
DISPLAY INVISIBLE (-3600 5200);
FORCEPROP 2 LAST CDS_LIB standard
J 0
(-3100 5150);
DISPLAY INVISIBLE (-3100 5150);
FORCEPROP 2 LAST BOM_COST IO_SLOT
J 0
(-3600 5250);
DISPLAY 0.829787 (-3600 5250);
DISPLAY INVISIBLE (-3600 5250);
FORCEPROP 1 LAST BODY_TYPE PLUMBING
J 2
(-3100 5100);
DISPLAY 0.702128 (-3100 5100);
PAINT GREEN (-3100 5100);
DISPLAY INVISIBLE (-3100 5100);
FORCEPROP 1 LAST HDL_TAP TRUE
J 2
(-3425 5025);
DISPLAY 0.702128 (-3425 5025);
PAINT GREEN (-3425 5025);
DISPLAY INVISIBLE (-3425 5025);
FORCEPROP 1 LAST PATH I246
J 2
(-3098 5150);
DISPLAY 0.872340 (-3098 5150);
PAINT GREEN (-3098 5150);
DISPLAY INVISIBLE (-3098 5150);
FORCEADD TAP..6
R 2
(-3100 5050);
FORCEPROP 3 LASTPIN (-3150 5050) SIG_NAME GMI_CPU1_G0_CPU0_G2_TX_DP<8>
J 0
(-3140 5060);
DISPLAY 0.659574 (-3140 5060);
PAINT MONO (-3140 5060);
DISPLAY INVISIBLE (-3140 5060);
FORCEPROP 1 LASTPIN (-3150 5050) BN 8
J 2
(-3098 5058);
DISPLAY 0.489362 (-3098 5058);
PAINT MONO (-3098 5058);
FORCEPROP 2 LAST ROOM RISER1
J 0
(-3600 5100);
DISPLAY 0.829787 (-3600 5100);
PAINT RED (-3600 5100);
DISPLAY INVISIBLE (-3600 5100);
FORCEPROP 2 LAST CDS_LIB standard
J 0
(-3100 5050);
DISPLAY INVISIBLE (-3100 5050);
FORCEPROP 2 LAST BOM_COST IO_SLOT
J 0
(-3600 5150);
DISPLAY 0.829787 (-3600 5150);
DISPLAY INVISIBLE (-3600 5150);
FORCEPROP 1 LAST BODY_TYPE PLUMBING
J 2
(-3100 5000);
DISPLAY 0.702128 (-3100 5000);
PAINT GREEN (-3100 5000);
DISPLAY INVISIBLE (-3100 5000);
FORCEPROP 1 LAST HDL_TAP TRUE
J 2
(-3425 4925);
DISPLAY 0.702128 (-3425 4925);
PAINT GREEN (-3425 4925);
DISPLAY INVISIBLE (-3425 4925);
FORCEPROP 1 LAST PATH I250
J 2
(-3098 5050);
DISPLAY 0.872340 (-3098 5050);
PAINT GREEN (-3098 5050);
DISPLAY INVISIBLE (-3098 5050);
FORCEADD TAP..6
R 2
(-3100 4950);
FORCEPROP 3 LASTPIN (-3150 4950) SIG_NAME GMI_CPU1_G0_CPU0_G2_TX_DP<7>
J 0
(-3140 4960);
DISPLAY 0.659574 (-3140 4960);
PAINT MONO (-3140 4960);
DISPLAY INVISIBLE (-3140 4960);
FORCEPROP 1 LASTPIN (-3150 4950) BN 7
J 2
(-3098 4958);
DISPLAY 0.489362 (-3098 4958);
PAINT MONO (-3098 4958);
FORCEPROP 2 LAST ROOM RISER1
J 0
(-3600 5000);
DISPLAY 0.829787 (-3600 5000);
PAINT RED (-3600 5000);
DISPLAY INVISIBLE (-3600 5000);
FORCEPROP 2 LAST CDS_LIB standard
J 0
(-3100 4950);
DISPLAY INVISIBLE (-3100 4950);
FORCEPROP 2 LAST BOM_COST IO_SLOT
J 0
(-3600 5050);
DISPLAY 0.829787 (-3600 5050);
DISPLAY INVISIBLE (-3600 5050);
FORCEPROP 1 LAST BODY_TYPE PLUMBING
J 2
(-3100 4900);
DISPLAY 0.702128 (-3100 4900);
PAINT GREEN (-3100 4900);
DISPLAY INVISIBLE (-3100 4900);
FORCEPROP 1 LAST HDL_TAP TRUE
J 2
(-3425 4825);
DISPLAY 0.702128 (-3425 4825);
PAINT GREEN (-3425 4825);
DISPLAY INVISIBLE (-3425 4825);
FORCEPROP 1 LAST PATH I251
J 2
(-3098 4950);
DISPLAY 0.872340 (-3098 4950);
PAINT GREEN (-3098 4950);
DISPLAY INVISIBLE (-3098 4950);
FORCEADD TAP..6
R 2
(-3100 4850);
FORCEPROP 3 LASTPIN (-3150 4850) SIG_NAME GMI_CPU1_G0_CPU0_G2_TX_DP<6>
J 0
(-3140 4860);
DISPLAY 0.659574 (-3140 4860);
PAINT MONO (-3140 4860);
DISPLAY INVISIBLE (-3140 4860);
FORCEPROP 1 LASTPIN (-3150 4850) BN 6
J 2
(-3098 4858);
DISPLAY 0.489362 (-3098 4858);
PAINT MONO (-3098 4858);
FORCEPROP 2 LAST ROOM RISER1
J 0
(-3600 4900);
DISPLAY 0.829787 (-3600 4900);
PAINT RED (-3600 4900);
DISPLAY INVISIBLE (-3600 4900);
FORCEPROP 2 LAST CDS_LIB standard
J 0
(-3100 4850);
DISPLAY INVISIBLE (-3100 4850);
FORCEPROP 2 LAST BOM_COST IO_SLOT
J 0
(-3600 4950);
DISPLAY 0.829787 (-3600 4950);
DISPLAY INVISIBLE (-3600 4950);
FORCEPROP 1 LAST BODY_TYPE PLUMBING
J 2
(-3100 4800);
DISPLAY 0.702128 (-3100 4800);
PAINT GREEN (-3100 4800);
DISPLAY INVISIBLE (-3100 4800);
FORCEPROP 1 LAST HDL_TAP TRUE
J 2
(-3425 4725);
DISPLAY 0.702128 (-3425 4725);
PAINT GREEN (-3425 4725);
DISPLAY INVISIBLE (-3425 4725);
FORCEPROP 1 LAST PATH I254
J 2
(-3098 4850);
DISPLAY 0.872340 (-3098 4850);
PAINT GREEN (-3098 4850);
DISPLAY INVISIBLE (-3098 4850);
FORCEADD TAP..6
R 2
(-3100 4750);
FORCEPROP 3 LASTPIN (-3150 4750) SIG_NAME GMI_CPU1_G0_CPU0_G2_TX_DP<5>
J 0
(-3140 4760);
DISPLAY 0.659574 (-3140 4760);
PAINT MONO (-3140 4760);
DISPLAY INVISIBLE (-3140 4760);
FORCEPROP 1 LASTPIN (-3150 4750) BN 5
J 2
(-3098 4758);
DISPLAY 0.489362 (-3098 4758);
PAINT MONO (-3098 4758);
FORCEPROP 2 LAST ROOM RISER1
J 0
(-3600 4800);
DISPLAY 0.829787 (-3600 4800);
PAINT RED (-3600 4800);
DISPLAY INVISIBLE (-3600 4800);
FORCEPROP 2 LAST CDS_LIB standard
J 0
(-3100 4750);
DISPLAY INVISIBLE (-3100 4750);
FORCEPROP 2 LAST BOM_COST IO_SLOT
J 0
(-3600 4850);
DISPLAY 0.829787 (-3600 4850);
DISPLAY INVISIBLE (-3600 4850);
FORCEPROP 1 LAST BODY_TYPE PLUMBING
J 2
(-3100 4700);
DISPLAY 0.702128 (-3100 4700);
PAINT GREEN (-3100 4700);
DISPLAY INVISIBLE (-3100 4700);
FORCEPROP 1 LAST HDL_TAP TRUE
J 2
(-3425 4625);
DISPLAY 0.702128 (-3425 4625);
PAINT GREEN (-3425 4625);
DISPLAY INVISIBLE (-3425 4625);
FORCEPROP 1 LAST PATH I255
J 2
(-3098 4750);
DISPLAY 0.872340 (-3098 4750);
PAINT GREEN (-3098 4750);
DISPLAY INVISIBLE (-3098 4750);
FORCEADD TAP..6
R 2
(-3100 4650);
FORCEPROP 3 LASTPIN (-3150 4650) SIG_NAME GMI_CPU1_G0_CPU0_G2_TX_DP<4>
J 0
(-3140 4660);
DISPLAY 0.659574 (-3140 4660);
PAINT MONO (-3140 4660);
DISPLAY INVISIBLE (-3140 4660);
FORCEPROP 1 LASTPIN (-3150 4650) BN 4
J 2
(-3098 4658);
DISPLAY 0.489362 (-3098 4658);
PAINT MONO (-3098 4658);
FORCEPROP 2 LAST ROOM RISER1
J 0
(-3600 4700);
DISPLAY 0.829787 (-3600 4700);
PAINT RED (-3600 4700);
DISPLAY INVISIBLE (-3600 4700);
FORCEPROP 2 LAST CDS_LIB standard
J 0
(-3100 4650);
DISPLAY INVISIBLE (-3100 4650);
FORCEPROP 2 LAST BOM_COST IO_SLOT
J 0
(-3600 4750);
DISPLAY 0.829787 (-3600 4750);
DISPLAY INVISIBLE (-3600 4750);
FORCEPROP 1 LAST BODY_TYPE PLUMBING
J 2
(-3100 4600);
DISPLAY 0.702128 (-3100 4600);
PAINT GREEN (-3100 4600);
DISPLAY INVISIBLE (-3100 4600);
FORCEPROP 1 LAST HDL_TAP TRUE
J 2
(-3425 4525);
DISPLAY 0.702128 (-3425 4525);
PAINT GREEN (-3425 4525);
DISPLAY INVISIBLE (-3425 4525);
FORCEPROP 1 LAST PATH I256
J 2
(-3098 4650);
DISPLAY 0.872340 (-3098 4650);
PAINT GREEN (-3098 4650);
DISPLAY INVISIBLE (-3098 4650);
FORCEADD TAP..6
R 2
(-3100 4550);
FORCEPROP 3 LASTPIN (-3150 4550) SIG_NAME GMI_CPU1_G0_CPU0_G2_TX_DP<3>
J 0
(-3140 4560);
DISPLAY 0.659574 (-3140 4560);
PAINT MONO (-3140 4560);
DISPLAY INVISIBLE (-3140 4560);
FORCEPROP 1 LASTPIN (-3150 4550) BN 3
J 2
(-3098 4558);
DISPLAY 0.489362 (-3098 4558);
PAINT MONO (-3098 4558);
FORCEPROP 2 LAST ROOM RISER1
J 0
(-3600 4600);
DISPLAY 0.829787 (-3600 4600);
PAINT RED (-3600 4600);
DISPLAY INVISIBLE (-3600 4600);
FORCEPROP 2 LAST CDS_LIB standard
J 0
(-3100 4550);
DISPLAY INVISIBLE (-3100 4550);
FORCEPROP 2 LAST BOM_COST IO_SLOT
J 0
(-3600 4650);
DISPLAY 0.829787 (-3600 4650);
DISPLAY INVISIBLE (-3600 4650);
FORCEPROP 1 LAST BODY_TYPE PLUMBING
J 2
(-3100 4500);
DISPLAY 0.702128 (-3100 4500);
PAINT GREEN (-3100 4500);
DISPLAY INVISIBLE (-3100 4500);
FORCEPROP 1 LAST HDL_TAP TRUE
J 2
(-3425 4425);
DISPLAY 0.702128 (-3425 4425);
PAINT GREEN (-3425 4425);
DISPLAY INVISIBLE (-3425 4425);
FORCEPROP 1 LAST PATH I260
J 2
(-3098 4550);
DISPLAY 0.872340 (-3098 4550);
PAINT GREEN (-3098 4550);
DISPLAY INVISIBLE (-3098 4550);
FORCEADD TAP..6
R 2
(-3100 4450);
FORCEPROP 3 LASTPIN (-3150 4450) SIG_NAME GMI_CPU1_G0_CPU0_G2_TX_DP<2>
J 0
(-3140 4460);
DISPLAY 0.659574 (-3140 4460);
PAINT MONO (-3140 4460);
DISPLAY INVISIBLE (-3140 4460);
FORCEPROP 1 LASTPIN (-3150 4450) BN 2
J 2
(-3098 4458);
DISPLAY 0.489362 (-3098 4458);
PAINT MONO (-3098 4458);
FORCEPROP 2 LAST ROOM RISER1
J 0
(-3600 4500);
DISPLAY 0.829787 (-3600 4500);
PAINT RED (-3600 4500);
DISPLAY INVISIBLE (-3600 4500);
FORCEPROP 2 LAST CDS_LIB standard
J 0
(-3100 4450);
DISPLAY INVISIBLE (-3100 4450);
FORCEPROP 2 LAST BOM_COST IO_SLOT
J 0
(-3600 4550);
DISPLAY 0.829787 (-3600 4550);
DISPLAY INVISIBLE (-3600 4550);
FORCEPROP 1 LAST BODY_TYPE PLUMBING
J 2
(-3100 4400);
DISPLAY 0.702128 (-3100 4400);
PAINT GREEN (-3100 4400);
DISPLAY INVISIBLE (-3100 4400);
FORCEPROP 1 LAST HDL_TAP TRUE
J 2
(-3425 4325);
DISPLAY 0.702128 (-3425 4325);
PAINT GREEN (-3425 4325);
DISPLAY INVISIBLE (-3425 4325);
FORCEPROP 1 LAST PATH I261
J 2
(-3098 4450);
DISPLAY 0.872340 (-3098 4450);
PAINT GREEN (-3098 4450);
DISPLAY INVISIBLE (-3098 4450);
FORCEADD TAP..6
R 2
(-3100 4350);
FORCEPROP 3 LASTPIN (-3150 4350) SIG_NAME GMI_CPU1_G0_CPU0_G2_TX_DP<1>
J 0
(-3140 4360);
DISPLAY 0.659574 (-3140 4360);
PAINT MONO (-3140 4360);
DISPLAY INVISIBLE (-3140 4360);
FORCEPROP 1 LASTPIN (-3150 4350) BN 1
J 2
(-3098 4358);
DISPLAY 0.489362 (-3098 4358);
PAINT MONO (-3098 4358);
FORCEPROP 2 LAST ROOM RISER1
J 0
(-3600 4400);
DISPLAY 0.829787 (-3600 4400);
PAINT RED (-3600 4400);
DISPLAY INVISIBLE (-3600 4400);
FORCEPROP 2 LAST CDS_LIB standard
J 0
(-3100 4350);
DISPLAY INVISIBLE (-3100 4350);
FORCEPROP 2 LAST BOM_COST IO_SLOT
J 0
(-3600 4450);
DISPLAY 0.829787 (-3600 4450);
DISPLAY INVISIBLE (-3600 4450);
FORCEPROP 1 LAST BODY_TYPE PLUMBING
J 2
(-3100 4300);
DISPLAY 0.702128 (-3100 4300);
PAINT GREEN (-3100 4300);
DISPLAY INVISIBLE (-3100 4300);
FORCEPROP 1 LAST HDL_TAP TRUE
J 2
(-3425 4225);
DISPLAY 0.702128 (-3425 4225);
PAINT GREEN (-3425 4225);
DISPLAY INVISIBLE (-3425 4225);
FORCEPROP 1 LAST PATH I264
J 2
(-3098 4350);
DISPLAY 0.872340 (-3098 4350);
PAINT GREEN (-3098 4350);
DISPLAY INVISIBLE (-3098 4350);
FORCEADD TAP..6
R 2
(-3100 4250);
FORCEPROP 3 LASTPIN (-3150 4250) SIG_NAME GMI_CPU1_G0_CPU0_G2_TX_DP<0>
J 0
(-3140 4260);
DISPLAY 0.659574 (-3140 4260);
PAINT MONO (-3140 4260);
DISPLAY INVISIBLE (-3140 4260);
FORCEPROP 1 LASTPIN (-3150 4250) BN 0
J 2
(-3098 4258);
DISPLAY 0.489362 (-3098 4258);
PAINT MONO (-3098 4258);
FORCEPROP 2 LAST ROOM RISER1
J 0
(-3600 4300);
DISPLAY 0.829787 (-3600 4300);
PAINT RED (-3600 4300);
DISPLAY INVISIBLE (-3600 4300);
FORCEPROP 2 LAST CDS_LIB standard
J 0
(-3100 4250);
DISPLAY INVISIBLE (-3100 4250);
FORCEPROP 2 LAST BOM_COST IO_SLOT
J 0
(-3600 4350);
DISPLAY 0.829787 (-3600 4350);
DISPLAY INVISIBLE (-3600 4350);
FORCEPROP 1 LAST BODY_TYPE PLUMBING
J 2
(-3100 4200);
DISPLAY 0.702128 (-3100 4200);
PAINT GREEN (-3100 4200);
DISPLAY INVISIBLE (-3100 4200);
FORCEPROP 1 LAST HDL_TAP TRUE
J 2
(-3425 4125);
DISPLAY 0.702128 (-3425 4125);
PAINT GREEN (-3425 4125);
DISPLAY INVISIBLE (-3425 4125);
FORCEPROP 1 LAST PATH I265
J 2
(-3098 4250);
DISPLAY 0.872340 (-3098 4250);
PAINT GREEN (-3098 4250);
DISPLAY INVISIBLE (-3098 4250);
FORCEADD OFFPAGE..2
(-1800 3250);
FORCEPROP 2 LAST $XR0 67 
J 0
(-1611 3250);
DISPLAY 0.638298 (-1611 3250);
PAINT MONO (-1611 3250);
FORCEPROP 2 LAST CDS_LIB standard
J 0
(-1800 3250);
DISPLAY INVISIBLE (-1800 3250);
FORCEPROP 1 LAST OFFPAGE TRUE
J 0
(-1475 3125);
DISPLAY 0.872340 (-1475 3125);
PAINT GREEN (-1475 3125);
DISPLAY INVISIBLE (-1475 3125);
FORCEPROP 1 LAST COMMENT_BODY TRUE
J 0
(-1845 3155);
DISPLAY 0.872340 (-1845 3155);
PAINT GREEN (-1845 3155);
DISPLAY INVISIBLE (-1845 3155);
FORCEPROP 2 LAST PATH I267
J 0
(-1600 3300);
DISPLAY 1.021277 (-1600 3300);
DISPLAY INVISIBLE (-1600 3300);
FORCEADD TAP..6
R 2
(-3075 2925);
FORCEPROP 3 LASTPIN (-3125 2925) SIG_NAME P5E_CPU1_G1_TX_DP<1>
J 0
(-3115 2935);
DISPLAY 0.659574 (-3115 2935);
PAINT MONO (-3115 2935);
DISPLAY INVISIBLE (-3115 2935);
FORCEPROP 1 LASTPIN (-3125 2925) BN 1
J 2
(-3073 2933);
DISPLAY 0.489362 (-3073 2933);
PAINT MONO (-3073 2933);
FORCEPROP 2 LAST ROOM RISER1
J 0
(-3575 2975);
DISPLAY 0.829787 (-3575 2975);
PAINT RED (-3575 2975);
DISPLAY INVISIBLE (-3575 2975);
FORCEPROP 2 LAST BOM_COST IO_SLOT
J 0
(-3575 3025);
DISPLAY 0.829787 (-3575 3025);
DISPLAY INVISIBLE (-3575 3025);
FORCEPROP 2 LAST CDS_LIB mstr_standard
J 0
(-3075 2925);
DISPLAY INVISIBLE (-3075 2925);
FORCEPROP 1 LAST BODY_TYPE PLUMBING
J 2
(-3075 2875);
DISPLAY 0.702128 (-3075 2875);
PAINT GREEN (-3075 2875);
DISPLAY INVISIBLE (-3075 2875);
FORCEPROP 1 LAST HDL_TAP TRUE
J 2
(-3400 2800);
DISPLAY 0.702128 (-3400 2800);
PAINT GREEN (-3400 2800);
DISPLAY INVISIBLE (-3400 2800);
FORCEPROP 1 LAST PATH I270
J 2
(-3073 2925);
DISPLAY 0.872340 (-3073 2925);
PAINT GREEN (-3073 2925);
DISPLAY INVISIBLE (-3073 2925);
FORCEADD TAP..6
R 2
(-3075 2825);
FORCEPROP 3 LASTPIN (-3125 2825) SIG_NAME P5E_CPU1_G1_TX_DP<2>
J 0
(-3115 2835);
DISPLAY 0.659574 (-3115 2835);
PAINT MONO (-3115 2835);
DISPLAY INVISIBLE (-3115 2835);
FORCEPROP 1 LASTPIN (-3125 2825) BN 2
J 2
(-3073 2833);
DISPLAY 0.489362 (-3073 2833);
PAINT MONO (-3073 2833);
FORCEPROP 2 LAST ROOM RISER1
J 0
(-3575 2875);
DISPLAY 0.829787 (-3575 2875);
PAINT RED (-3575 2875);
DISPLAY INVISIBLE (-3575 2875);
FORCEPROP 2 LAST BOM_COST IO_SLOT
J 0
(-3575 2925);
DISPLAY 0.829787 (-3575 2925);
DISPLAY INVISIBLE (-3575 2925);
FORCEPROP 2 LAST CDS_LIB standard
J 0
(-3075 2825);
DISPLAY INVISIBLE (-3075 2825);
FORCEPROP 1 LAST BODY_TYPE PLUMBING
J 2
(-3075 2775);
DISPLAY 0.702128 (-3075 2775);
PAINT GREEN (-3075 2775);
DISPLAY INVISIBLE (-3075 2775);
FORCEPROP 1 LAST HDL_TAP TRUE
J 2
(-3400 2700);
DISPLAY 0.702128 (-3400 2700);
PAINT GREEN (-3400 2700);
DISPLAY INVISIBLE (-3400 2700);
FORCEPROP 1 LAST PATH I271
J 2
(-3073 2825);
DISPLAY 0.872340 (-3073 2825);
PAINT GREEN (-3073 2825);
DISPLAY INVISIBLE (-3073 2825);
FORCEADD TAP..6
R 2
(-3075 3025);
FORCEPROP 3 LASTPIN (-3125 3025) SIG_NAME P5E_CPU1_G1_TX_DP<0>
J 0
(-3115 3035);
DISPLAY 0.659574 (-3115 3035);
PAINT MONO (-3115 3035);
DISPLAY INVISIBLE (-3115 3035);
FORCEPROP 1 LASTPIN (-3125 3025) BN 0
J 2
(-3073 3033);
DISPLAY 0.489362 (-3073 3033);
PAINT MONO (-3073 3033);
FORCEPROP 2 LAST ROOM RISER1
J 0
(-3575 3075);
DISPLAY 0.829787 (-3575 3075);
PAINT RED (-3575 3075);
DISPLAY INVISIBLE (-3575 3075);
FORCEPROP 2 LAST BOM_COST IO_SLOT
J 0
(-3575 3125);
DISPLAY 0.829787 (-3575 3125);
DISPLAY INVISIBLE (-3575 3125);
FORCEPROP 2 LAST CDS_LIB mstr_standard
J 0
(-3075 3025);
DISPLAY INVISIBLE (-3075 3025);
FORCEPROP 1 LAST BODY_TYPE PLUMBING
J 2
(-3075 2975);
DISPLAY 0.702128 (-3075 2975);
PAINT GREEN (-3075 2975);
DISPLAY INVISIBLE (-3075 2975);
FORCEPROP 1 LAST HDL_TAP TRUE
J 2
(-3400 2900);
DISPLAY 0.702128 (-3400 2900);
PAINT GREEN (-3400 2900);
DISPLAY INVISIBLE (-3400 2900);
FORCEPROP 1 LAST PATH I272
J 2
(-3073 3025);
DISPLAY 0.872340 (-3073 3025);
PAINT GREEN (-3073 3025);
DISPLAY INVISIBLE (-3073 3025);
FORCEADD TAP..6
R 2
(-3075 2725);
FORCEPROP 3 LASTPIN (-3125 2725) SIG_NAME P5E_CPU1_G1_TX_DP<3>
J 0
(-3115 2735);
DISPLAY 0.659574 (-3115 2735);
PAINT MONO (-3115 2735);
DISPLAY INVISIBLE (-3115 2735);
FORCEPROP 1 LASTPIN (-3125 2725) BN 3
J 2
(-3073 2733);
DISPLAY 0.489362 (-3073 2733);
PAINT MONO (-3073 2733);
FORCEPROP 2 LAST ROOM RISER1
J 0
(-3575 2775);
DISPLAY 0.829787 (-3575 2775);
PAINT RED (-3575 2775);
DISPLAY INVISIBLE (-3575 2775);
FORCEPROP 2 LAST BOM_COST IO_SLOT
J 0
(-3575 2825);
DISPLAY 0.829787 (-3575 2825);
DISPLAY INVISIBLE (-3575 2825);
FORCEPROP 2 LAST CDS_LIB standard
J 0
(-3075 2725);
DISPLAY INVISIBLE (-3075 2725);
FORCEPROP 1 LAST BODY_TYPE PLUMBING
J 2
(-3075 2675);
DISPLAY 0.702128 (-3075 2675);
PAINT GREEN (-3075 2675);
DISPLAY INVISIBLE (-3075 2675);
FORCEPROP 1 LAST HDL_TAP TRUE
J 2
(-3400 2600);
DISPLAY 0.702128 (-3400 2600);
PAINT GREEN (-3400 2600);
DISPLAY INVISIBLE (-3400 2600);
FORCEPROP 1 LAST PATH I276
J 2
(-3073 2725);
DISPLAY 0.872340 (-3073 2725);
PAINT GREEN (-3073 2725);
DISPLAY INVISIBLE (-3073 2725);
FORCEADD TAP..6
R 2
(-3075 2625);
FORCEPROP 3 LASTPIN (-3125 2625) SIG_NAME P5E_CPU1_G1_TX_DP<4>
J 0
(-3115 2635);
DISPLAY 0.659574 (-3115 2635);
PAINT MONO (-3115 2635);
DISPLAY INVISIBLE (-3115 2635);
FORCEPROP 1 LASTPIN (-3125 2625) BN 4
J 2
(-3073 2633);
DISPLAY 0.489362 (-3073 2633);
PAINT MONO (-3073 2633);
FORCEPROP 2 LAST ROOM RISER1
J 0
(-3575 2675);
DISPLAY 0.829787 (-3575 2675);
PAINT RED (-3575 2675);
DISPLAY INVISIBLE (-3575 2675);
FORCEPROP 2 LAST BOM_COST IO_SLOT
J 0
(-3575 2725);
DISPLAY 0.829787 (-3575 2725);
DISPLAY INVISIBLE (-3575 2725);
FORCEPROP 2 LAST CDS_LIB standard
J 0
(-3075 2625);
DISPLAY INVISIBLE (-3075 2625);
FORCEPROP 1 LAST BODY_TYPE PLUMBING
J 2
(-3075 2575);
DISPLAY 0.702128 (-3075 2575);
PAINT GREEN (-3075 2575);
DISPLAY INVISIBLE (-3075 2575);
FORCEPROP 1 LAST HDL_TAP TRUE
J 2
(-3400 2500);
DISPLAY 0.702128 (-3400 2500);
PAINT GREEN (-3400 2500);
DISPLAY INVISIBLE (-3400 2500);
FORCEPROP 1 LAST PATH I277
J 2
(-3073 2625);
DISPLAY 0.872340 (-3073 2625);
PAINT GREEN (-3073 2625);
DISPLAY INVISIBLE (-3073 2625);
FORCEADD TAP..6
R 2
(-3075 2425);
FORCEPROP 3 LASTPIN (-3125 2425) SIG_NAME P5E_CPU1_G1_TX_DP<6>
J 0
(-3115 2435);
DISPLAY 0.659574 (-3115 2435);
PAINT MONO (-3115 2435);
DISPLAY INVISIBLE (-3115 2435);
FORCEPROP 1 LASTPIN (-3125 2425) BN 6
J 2
(-3073 2433);
DISPLAY 0.489362 (-3073 2433);
PAINT MONO (-3073 2433);
FORCEPROP 2 LAST ROOM RISER1
J 0
(-3575 2475);
DISPLAY 0.829787 (-3575 2475);
PAINT RED (-3575 2475);
DISPLAY INVISIBLE (-3575 2475);
FORCEPROP 2 LAST BOM_COST IO_SLOT
J 0
(-3575 2525);
DISPLAY 0.829787 (-3575 2525);
DISPLAY INVISIBLE (-3575 2525);
FORCEPROP 2 LAST CDS_LIB standard
J 0
(-3075 2425);
DISPLAY INVISIBLE (-3075 2425);
FORCEPROP 1 LAST BODY_TYPE PLUMBING
J 2
(-3075 2375);
DISPLAY 0.702128 (-3075 2375);
PAINT GREEN (-3075 2375);
DISPLAY INVISIBLE (-3075 2375);
FORCEPROP 1 LAST HDL_TAP TRUE
J 2
(-3400 2300);
DISPLAY 0.702128 (-3400 2300);
PAINT GREEN (-3400 2300);
DISPLAY INVISIBLE (-3400 2300);
FORCEPROP 1 LAST PATH I280
J 2
(-3073 2425);
DISPLAY 0.872340 (-3073 2425);
PAINT GREEN (-3073 2425);
DISPLAY INVISIBLE (-3073 2425);
FORCEADD TAP..6
R 2
(-3075 2325);
FORCEPROP 3 LASTPIN (-3125 2325) SIG_NAME P5E_CPU1_G1_TX_DP<7>
J 0
(-3115 2335);
DISPLAY 0.659574 (-3115 2335);
PAINT MONO (-3115 2335);
DISPLAY INVISIBLE (-3115 2335);
FORCEPROP 1 LASTPIN (-3125 2325) BN 7
J 2
(-3073 2333);
DISPLAY 0.489362 (-3073 2333);
PAINT MONO (-3073 2333);
FORCEPROP 2 LAST ROOM RISER1
J 0
(-3575 2375);
DISPLAY 0.829787 (-3575 2375);
PAINT RED (-3575 2375);
DISPLAY INVISIBLE (-3575 2375);
FORCEPROP 2 LAST BOM_COST IO_SLOT
J 0
(-3575 2425);
DISPLAY 0.829787 (-3575 2425);
DISPLAY INVISIBLE (-3575 2425);
FORCEPROP 2 LAST CDS_LIB standard
J 0
(-3075 2325);
DISPLAY INVISIBLE (-3075 2325);
FORCEPROP 1 LAST BODY_TYPE PLUMBING
J 2
(-3075 2275);
DISPLAY 0.702128 (-3075 2275);
PAINT GREEN (-3075 2275);
DISPLAY INVISIBLE (-3075 2275);
FORCEPROP 1 LAST HDL_TAP TRUE
J 2
(-3400 2200);
DISPLAY 0.702128 (-3400 2200);
PAINT GREEN (-3400 2200);
DISPLAY INVISIBLE (-3400 2200);
FORCEPROP 1 LAST PATH I281
J 2
(-3073 2325);
DISPLAY 0.872340 (-3073 2325);
PAINT GREEN (-3073 2325);
DISPLAY INVISIBLE (-3073 2325);
FORCEADD TAP..6
R 2
(-3075 2525);
FORCEPROP 3 LASTPIN (-3125 2525) SIG_NAME P5E_CPU1_G1_TX_DP<5>
J 0
(-3115 2535);
DISPLAY 0.659574 (-3115 2535);
PAINT MONO (-3115 2535);
DISPLAY INVISIBLE (-3115 2535);
FORCEPROP 1 LASTPIN (-3125 2525) BN 5
J 2
(-3073 2533);
DISPLAY 0.489362 (-3073 2533);
PAINT MONO (-3073 2533);
FORCEPROP 2 LAST ROOM RISER1
J 0
(-3575 2575);
DISPLAY 0.829787 (-3575 2575);
PAINT RED (-3575 2575);
DISPLAY INVISIBLE (-3575 2575);
FORCEPROP 2 LAST BOM_COST IO_SLOT
J 0
(-3575 2625);
DISPLAY 0.829787 (-3575 2625);
DISPLAY INVISIBLE (-3575 2625);
FORCEPROP 2 LAST CDS_LIB standard
J 0
(-3075 2525);
DISPLAY INVISIBLE (-3075 2525);
FORCEPROP 1 LAST BODY_TYPE PLUMBING
J 2
(-3075 2475);
DISPLAY 0.702128 (-3075 2475);
PAINT GREEN (-3075 2475);
DISPLAY INVISIBLE (-3075 2475);
FORCEPROP 1 LAST HDL_TAP TRUE
J 2
(-3400 2400);
DISPLAY 0.702128 (-3400 2400);
PAINT GREEN (-3400 2400);
DISPLAY INVISIBLE (-3400 2400);
FORCEPROP 1 LAST PATH I282
J 2
(-3073 2525);
DISPLAY 0.872340 (-3073 2525);
PAINT GREEN (-3073 2525);
DISPLAY INVISIBLE (-3073 2525);
FORCEADD TAP..6
R 2
(-3075 2225);
FORCEPROP 3 LASTPIN (-3125 2225) SIG_NAME P5E_CPU1_G1_TX_DP<8>
J 0
(-3115 2235);
DISPLAY 0.659574 (-3115 2235);
PAINT MONO (-3115 2235);
DISPLAY INVISIBLE (-3115 2235);
FORCEPROP 1 LASTPIN (-3125 2225) BN 8
J 2
(-3073 2233);
DISPLAY 0.489362 (-3073 2233);
PAINT MONO (-3073 2233);
FORCEPROP 2 LAST ROOM RISER1
J 0
(-3575 2275);
DISPLAY 0.829787 (-3575 2275);
PAINT RED (-3575 2275);
DISPLAY INVISIBLE (-3575 2275);
FORCEPROP 2 LAST BOM_COST IO_SLOT
J 0
(-3575 2325);
DISPLAY 0.829787 (-3575 2325);
DISPLAY INVISIBLE (-3575 2325);
FORCEPROP 2 LAST CDS_LIB standard
J 0
(-3075 2225);
DISPLAY INVISIBLE (-3075 2225);
FORCEPROP 1 LAST BODY_TYPE PLUMBING
J 2
(-3075 2175);
DISPLAY 0.702128 (-3075 2175);
PAINT GREEN (-3075 2175);
DISPLAY INVISIBLE (-3075 2175);
FORCEPROP 1 LAST HDL_TAP TRUE
J 2
(-3400 2100);
DISPLAY 0.702128 (-3400 2100);
PAINT GREEN (-3400 2100);
DISPLAY INVISIBLE (-3400 2100);
FORCEPROP 1 LAST PATH I286
J 2
(-3073 2225);
DISPLAY 0.872340 (-3073 2225);
PAINT GREEN (-3073 2225);
DISPLAY INVISIBLE (-3073 2225);
FORCEADD TAP..6
R 2
(-3075 2125);
FORCEPROP 3 LASTPIN (-3125 2125) SIG_NAME P5E_CPU1_G1_TX_DP<9>
J 0
(-3115 2135);
DISPLAY 0.659574 (-3115 2135);
PAINT MONO (-3115 2135);
DISPLAY INVISIBLE (-3115 2135);
FORCEPROP 1 LASTPIN (-3125 2125) BN 9
J 2
(-3073 2133);
DISPLAY 0.489362 (-3073 2133);
PAINT MONO (-3073 2133);
FORCEPROP 2 LAST ROOM RISER1
J 0
(-3575 2175);
DISPLAY 0.829787 (-3575 2175);
PAINT RED (-3575 2175);
DISPLAY INVISIBLE (-3575 2175);
FORCEPROP 2 LAST BOM_COST IO_SLOT
J 0
(-3575 2225);
DISPLAY 0.829787 (-3575 2225);
DISPLAY INVISIBLE (-3575 2225);
FORCEPROP 2 LAST CDS_LIB standard
J 0
(-3075 2125);
DISPLAY INVISIBLE (-3075 2125);
FORCEPROP 1 LAST BODY_TYPE PLUMBING
J 2
(-3075 2075);
DISPLAY 0.702128 (-3075 2075);
PAINT GREEN (-3075 2075);
DISPLAY INVISIBLE (-3075 2075);
FORCEPROP 1 LAST HDL_TAP TRUE
J 2
(-3400 2000);
DISPLAY 0.702128 (-3400 2000);
PAINT GREEN (-3400 2000);
DISPLAY INVISIBLE (-3400 2000);
FORCEPROP 1 LAST PATH I287
J 2
(-3073 2125);
DISPLAY 0.872340 (-3073 2125);
PAINT GREEN (-3073 2125);
DISPLAY INVISIBLE (-3073 2125);
FORCEADD TAP..6
R 2
(-3075 1925);
FORCEPROP 3 LASTPIN (-3125 1925) SIG_NAME P5E_CPU1_G1_TX_DP<11>
J 0
(-3115 1935);
DISPLAY 0.659574 (-3115 1935);
PAINT MONO (-3115 1935);
DISPLAY INVISIBLE (-3115 1935);
FORCEPROP 1 LASTPIN (-3125 1925) BN 11
J 2
(-3073 1933);
DISPLAY 0.489362 (-3073 1933);
PAINT MONO (-3073 1933);
FORCEPROP 2 LAST ROOM RISER1
J 0
(-3575 1975);
DISPLAY 0.829787 (-3575 1975);
PAINT RED (-3575 1975);
DISPLAY INVISIBLE (-3575 1975);
FORCEPROP 2 LAST BOM_COST IO_SLOT
J 0
(-3575 2025);
DISPLAY 0.829787 (-3575 2025);
DISPLAY INVISIBLE (-3575 2025);
FORCEPROP 2 LAST CDS_LIB standard
J 0
(-3075 1925);
DISPLAY INVISIBLE (-3075 1925);
FORCEPROP 1 LAST BODY_TYPE PLUMBING
J 2
(-3075 1875);
DISPLAY 0.702128 (-3075 1875);
PAINT GREEN (-3075 1875);
DISPLAY INVISIBLE (-3075 1875);
FORCEPROP 1 LAST HDL_TAP TRUE
J 2
(-3400 1800);
DISPLAY 0.702128 (-3400 1800);
PAINT GREEN (-3400 1800);
DISPLAY INVISIBLE (-3400 1800);
FORCEPROP 1 LAST PATH I290
J 2
(-3073 1925);
DISPLAY 0.872340 (-3073 1925);
PAINT GREEN (-3073 1925);
DISPLAY INVISIBLE (-3073 1925);
FORCEADD TAP..6
R 2
(-3075 1825);
FORCEPROP 3 LASTPIN (-3125 1825) SIG_NAME P5E_CPU1_G1_TX_DP<12>
J 0
(-3115 1835);
DISPLAY 0.659574 (-3115 1835);
PAINT MONO (-3115 1835);
DISPLAY INVISIBLE (-3115 1835);
FORCEPROP 1 LASTPIN (-3125 1825) BN 12
J 2
(-3073 1833);
DISPLAY 0.489362 (-3073 1833);
PAINT MONO (-3073 1833);
FORCEPROP 2 LAST ROOM RISER1
J 0
(-3575 1875);
DISPLAY 0.829787 (-3575 1875);
PAINT RED (-3575 1875);
DISPLAY INVISIBLE (-3575 1875);
FORCEPROP 2 LAST BOM_COST IO_SLOT
J 0
(-3575 1925);
DISPLAY 0.829787 (-3575 1925);
DISPLAY INVISIBLE (-3575 1925);
FORCEPROP 2 LAST CDS_LIB standard
J 0
(-3075 1825);
DISPLAY INVISIBLE (-3075 1825);
FORCEPROP 1 LAST BODY_TYPE PLUMBING
J 2
(-3075 1775);
DISPLAY 0.702128 (-3075 1775);
PAINT GREEN (-3075 1775);
DISPLAY INVISIBLE (-3075 1775);
FORCEPROP 1 LAST HDL_TAP TRUE
J 2
(-3400 1700);
DISPLAY 0.702128 (-3400 1700);
PAINT GREEN (-3400 1700);
DISPLAY INVISIBLE (-3400 1700);
FORCEPROP 1 LAST PATH I291
J 2
(-3073 1825);
DISPLAY 0.872340 (-3073 1825);
PAINT GREEN (-3073 1825);
DISPLAY INVISIBLE (-3073 1825);
FORCEADD TAP..6
R 2
(-3075 2025);
FORCEPROP 3 LASTPIN (-3125 2025) SIG_NAME P5E_CPU1_G1_TX_DP<10>
J 0
(-3115 2035);
DISPLAY 0.659574 (-3115 2035);
PAINT MONO (-3115 2035);
DISPLAY INVISIBLE (-3115 2035);
FORCEPROP 1 LASTPIN (-3125 2025) BN 10
J 2
(-3073 2033);
DISPLAY 0.489362 (-3073 2033);
PAINT MONO (-3073 2033);
FORCEPROP 2 LAST ROOM RISER1
J 0
(-3575 2075);
DISPLAY 0.829787 (-3575 2075);
PAINT RED (-3575 2075);
DISPLAY INVISIBLE (-3575 2075);
FORCEPROP 2 LAST BOM_COST IO_SLOT
J 0
(-3575 2125);
DISPLAY 0.829787 (-3575 2125);
DISPLAY INVISIBLE (-3575 2125);
FORCEPROP 2 LAST CDS_LIB standard
J 0
(-3075 2025);
DISPLAY INVISIBLE (-3075 2025);
FORCEPROP 1 LAST BODY_TYPE PLUMBING
J 2
(-3075 1975);
DISPLAY 0.702128 (-3075 1975);
PAINT GREEN (-3075 1975);
DISPLAY INVISIBLE (-3075 1975);
FORCEPROP 1 LAST HDL_TAP TRUE
J 2
(-3400 1900);
DISPLAY 0.702128 (-3400 1900);
PAINT GREEN (-3400 1900);
DISPLAY INVISIBLE (-3400 1900);
FORCEPROP 1 LAST PATH I292
J 2
(-3073 2025);
DISPLAY 0.872340 (-3073 2025);
PAINT GREEN (-3073 2025);
DISPLAY INVISIBLE (-3073 2025);
FORCEADD TAP..6
R 2
(-3075 1725);
FORCEPROP 3 LASTPIN (-3125 1725) SIG_NAME P5E_CPU1_G1_TX_DP<13>
J 0
(-3115 1735);
DISPLAY 0.659574 (-3115 1735);
PAINT MONO (-3115 1735);
DISPLAY INVISIBLE (-3115 1735);
FORCEPROP 1 LASTPIN (-3125 1725) BN 13
J 2
(-3073 1733);
DISPLAY 0.489362 (-3073 1733);
PAINT MONO (-3073 1733);
FORCEPROP 2 LAST ROOM RISER1
J 0
(-3575 1775);
DISPLAY 0.829787 (-3575 1775);
PAINT RED (-3575 1775);
DISPLAY INVISIBLE (-3575 1775);
FORCEPROP 2 LAST BOM_COST IO_SLOT
J 0
(-3575 1825);
DISPLAY 0.829787 (-3575 1825);
DISPLAY INVISIBLE (-3575 1825);
FORCEPROP 2 LAST CDS_LIB standard
J 0
(-3075 1725);
DISPLAY INVISIBLE (-3075 1725);
FORCEPROP 1 LAST BODY_TYPE PLUMBING
J 2
(-3075 1675);
DISPLAY 0.702128 (-3075 1675);
PAINT GREEN (-3075 1675);
DISPLAY INVISIBLE (-3075 1675);
FORCEPROP 1 LAST HDL_TAP TRUE
J 2
(-3400 1600);
DISPLAY 0.702128 (-3400 1600);
PAINT GREEN (-3400 1600);
DISPLAY INVISIBLE (-3400 1600);
FORCEPROP 1 LAST PATH I296
J 2
(-3073 1725);
DISPLAY 0.872340 (-3073 1725);
PAINT GREEN (-3073 1725);
DISPLAY INVISIBLE (-3073 1725);
FORCEADD TAP..6
R 2
(-3075 1625);
FORCEPROP 3 LASTPIN (-3125 1625) SIG_NAME P5E_CPU1_G1_TX_DP<14>
J 0
(-3115 1635);
DISPLAY 0.659574 (-3115 1635);
PAINT MONO (-3115 1635);
DISPLAY INVISIBLE (-3115 1635);
FORCEPROP 1 LASTPIN (-3125 1625) BN 14
J 2
(-3073 1633);
DISPLAY 0.489362 (-3073 1633);
PAINT MONO (-3073 1633);
FORCEPROP 2 LAST ROOM RISER1
J 0
(-3575 1675);
DISPLAY 0.829787 (-3575 1675);
PAINT RED (-3575 1675);
DISPLAY INVISIBLE (-3575 1675);
FORCEPROP 2 LAST BOM_COST IO_SLOT
J 0
(-3575 1725);
DISPLAY 0.829787 (-3575 1725);
DISPLAY INVISIBLE (-3575 1725);
FORCEPROP 2 LAST CDS_LIB standard
J 0
(-3075 1625);
DISPLAY INVISIBLE (-3075 1625);
FORCEPROP 1 LAST BODY_TYPE PLUMBING
J 2
(-3075 1575);
DISPLAY 0.702128 (-3075 1575);
PAINT GREEN (-3075 1575);
DISPLAY INVISIBLE (-3075 1575);
FORCEPROP 1 LAST HDL_TAP TRUE
J 2
(-3400 1500);
DISPLAY 0.702128 (-3400 1500);
PAINT GREEN (-3400 1500);
DISPLAY INVISIBLE (-3400 1500);
FORCEPROP 1 LAST PATH I297
J 2
(-3073 1625);
DISPLAY 0.872340 (-3073 1625);
PAINT GREEN (-3073 1625);
DISPLAY INVISIBLE (-3073 1625);
FORCEADD TAP..6
R 2
(-3075 1525);
FORCEPROP 3 LASTPIN (-3125 1525) SIG_NAME P5E_CPU1_G1_TX_DP<15>
J 0
(-3115 1535);
DISPLAY 0.659574 (-3115 1535);
PAINT MONO (-3115 1535);
DISPLAY INVISIBLE (-3115 1535);
FORCEPROP 1 LASTPIN (-3125 1525) BN 15
J 2
(-3073 1533);
DISPLAY 0.489362 (-3073 1533);
PAINT MONO (-3073 1533);
FORCEPROP 2 LAST ROOM RISER1
J 0
(-3575 1575);
DISPLAY 0.829787 (-3575 1575);
PAINT RED (-3575 1575);
DISPLAY INVISIBLE (-3575 1575);
FORCEPROP 2 LAST BOM_COST IO_SLOT
J 0
(-3575 1625);
DISPLAY 0.829787 (-3575 1625);
DISPLAY INVISIBLE (-3575 1625);
FORCEPROP 2 LAST CDS_LIB standard
J 0
(-3075 1525);
DISPLAY INVISIBLE (-3075 1525);
FORCEPROP 1 LAST BODY_TYPE PLUMBING
J 2
(-3075 1475);
DISPLAY 0.702128 (-3075 1475);
PAINT GREEN (-3075 1475);
DISPLAY INVISIBLE (-3075 1475);
FORCEPROP 1 LAST HDL_TAP TRUE
J 2
(-3400 1400);
DISPLAY 0.702128 (-3400 1400);
PAINT GREEN (-3400 1400);
DISPLAY INVISIBLE (-3400 1400);
FORCEPROP 1 LAST PATH I298
J 2
(-3073 1525);
DISPLAY 0.872340 (-3073 1525);
PAINT GREEN (-3073 1525);
DISPLAY INVISIBLE (-3073 1525);
FORCEADD TAP..6
(-6525 5750);
FORCEPROP 3 LASTPIN (-6475 5750) SIG_NAME GMI_CPU0_G2_CPU1_G0_TX_DP<15>
J 0
(-6465 5760);
DISPLAY 0.659574 (-6465 5760);
PAINT MONO (-6465 5760);
DISPLAY INVISIBLE (-6465 5760);
FORCEPROP 1 LASTPIN (-6475 5750) BN 15
J 0
(-6527 5758);
DISPLAY 0.489362 (-6527 5758);
PAINT MONO (-6527 5758);
FORCEPROP 2 LAST CDS_LIB mstr_standard
J 0
(-6525 5750);
DISPLAY INVISIBLE (-6525 5750);
FORCEPROP 1 LAST BODY_TYPE PLUMBING
J 0
(-6525 5700);
DISPLAY 0.574468 (-6525 5700);
PAINT GREEN (-6525 5700);
DISPLAY INVISIBLE (-6525 5700);
FORCEPROP 1 LAST HDL_TAP TRUE
J 0
(-6200 5625);
DISPLAY 0.574468 (-6200 5625);
PAINT GREEN (-6200 5625);
DISPLAY INVISIBLE (-6200 5625);
FORCEPROP 1 LAST PATH I300
J 0
(-6527 5750);
DISPLAY 0.872340 (-6527 5750);
PAINT GREEN (-6527 5750);
DISPLAY INVISIBLE (-6527 5750);
FORCEADD TAP..6
(-6525 5650);
FORCEPROP 3 LASTPIN (-6475 5650) SIG_NAME GMI_CPU0_G2_CPU1_G0_TX_DP<14>
J 0
(-6465 5660);
DISPLAY 0.659574 (-6465 5660);
PAINT MONO (-6465 5660);
DISPLAY INVISIBLE (-6465 5660);
FORCEPROP 1 LASTPIN (-6475 5650) BN 14
J 0
(-6527 5658);
DISPLAY 0.489362 (-6527 5658);
PAINT MONO (-6527 5658);
FORCEPROP 2 LAST CDS_LIB mstr_standard
J 0
(-6525 5650);
DISPLAY INVISIBLE (-6525 5650);
FORCEPROP 1 LAST BODY_TYPE PLUMBING
J 0
(-6525 5600);
DISPLAY 0.574468 (-6525 5600);
PAINT GREEN (-6525 5600);
DISPLAY INVISIBLE (-6525 5600);
FORCEPROP 1 LAST HDL_TAP TRUE
J 0
(-6200 5525);
DISPLAY 0.574468 (-6200 5525);
PAINT GREEN (-6200 5525);
DISPLAY INVISIBLE (-6200 5525);
FORCEPROP 1 LAST PATH I301
J 0
(-6527 5650);
DISPLAY 0.872340 (-6527 5650);
PAINT GREEN (-6527 5650);
DISPLAY INVISIBLE (-6527 5650);
FORCEADD TAP..6
(-6525 5550);
FORCEPROP 3 LASTPIN (-6475 5550) SIG_NAME GMI_CPU0_G2_CPU1_G0_TX_DP<13>
J 0
(-6465 5560);
DISPLAY 0.659574 (-6465 5560);
PAINT MONO (-6465 5560);
DISPLAY INVISIBLE (-6465 5560);
FORCEPROP 1 LASTPIN (-6475 5550) BN 13
J 0
(-6527 5558);
DISPLAY 0.489362 (-6527 5558);
PAINT MONO (-6527 5558);
FORCEPROP 2 LAST CDS_LIB mstr_standard
J 0
(-6525 5550);
DISPLAY INVISIBLE (-6525 5550);
FORCEPROP 1 LAST BODY_TYPE PLUMBING
J 0
(-6525 5500);
DISPLAY 0.574468 (-6525 5500);
PAINT GREEN (-6525 5500);
DISPLAY INVISIBLE (-6525 5500);
FORCEPROP 1 LAST HDL_TAP TRUE
J 0
(-6200 5425);
DISPLAY 0.574468 (-6200 5425);
PAINT GREEN (-6200 5425);
DISPLAY INVISIBLE (-6200 5425);
FORCEPROP 1 LAST PATH I303
J 0
(-6527 5550);
DISPLAY 0.872340 (-6527 5550);
PAINT GREEN (-6527 5550);
DISPLAY INVISIBLE (-6527 5550);
FORCEADD TAP..6
(-6525 5450);
FORCEPROP 3 LASTPIN (-6475 5450) SIG_NAME GMI_CPU0_G2_CPU1_G0_TX_DP<12>
J 0
(-6465 5460);
DISPLAY 0.659574 (-6465 5460);
PAINT MONO (-6465 5460);
DISPLAY INVISIBLE (-6465 5460);
FORCEPROP 1 LASTPIN (-6475 5450) BN 12
J 0
(-6527 5458);
DISPLAY 0.489362 (-6527 5458);
PAINT MONO (-6527 5458);
FORCEPROP 2 LAST CDS_LIB standard
J 0
(-6525 5450);
DISPLAY INVISIBLE (-6525 5450);
FORCEPROP 1 LAST BODY_TYPE PLUMBING
J 0
(-6525 5400);
DISPLAY 0.574468 (-6525 5400);
PAINT GREEN (-6525 5400);
DISPLAY INVISIBLE (-6525 5400);
FORCEPROP 1 LAST HDL_TAP TRUE
J 0
(-6200 5325);
DISPLAY 0.574468 (-6200 5325);
PAINT GREEN (-6200 5325);
DISPLAY INVISIBLE (-6200 5325);
FORCEPROP 1 LAST PATH I304
J 0
(-6527 5450);
DISPLAY 0.872340 (-6527 5450);
PAINT GREEN (-6527 5450);
DISPLAY INVISIBLE (-6527 5450);
FORCEADD TAP..6
(-6525 5250);
FORCEPROP 3 LASTPIN (-6475 5250) SIG_NAME GMI_CPU0_G2_CPU1_G0_TX_DP<10>
J 0
(-6465 5260);
DISPLAY 0.659574 (-6465 5260);
PAINT MONO (-6465 5260);
DISPLAY INVISIBLE (-6465 5260);
FORCEPROP 1 LASTPIN (-6475 5250) BN 10
J 0
(-6527 5258);
DISPLAY 0.489362 (-6527 5258);
PAINT MONO (-6527 5258);
FORCEPROP 2 LAST CDS_LIB standard
J 0
(-6525 5250);
DISPLAY INVISIBLE (-6525 5250);
FORCEPROP 1 LAST BODY_TYPE PLUMBING
J 0
(-6525 5200);
DISPLAY 0.574468 (-6525 5200);
PAINT GREEN (-6525 5200);
DISPLAY INVISIBLE (-6525 5200);
FORCEPROP 1 LAST HDL_TAP TRUE
J 0
(-6200 5125);
DISPLAY 0.574468 (-6200 5125);
PAINT GREEN (-6200 5125);
DISPLAY INVISIBLE (-6200 5125);
FORCEPROP 1 LAST PATH I308
J 0
(-6527 5250);
DISPLAY 0.872340 (-6527 5250);
PAINT GREEN (-6527 5250);
DISPLAY INVISIBLE (-6527 5250);
FORCEADD TAP..6
(-6525 5350);
FORCEPROP 3 LASTPIN (-6475 5350) SIG_NAME GMI_CPU0_G2_CPU1_G0_TX_DP<11>
J 0
(-6465 5360);
DISPLAY 0.659574 (-6465 5360);
PAINT MONO (-6465 5360);
DISPLAY INVISIBLE (-6465 5360);
FORCEPROP 1 LASTPIN (-6475 5350) BN 11
J 0
(-6527 5358);
DISPLAY 0.489362 (-6527 5358);
PAINT MONO (-6527 5358);
FORCEPROP 2 LAST CDS_LIB standard
J 0
(-6525 5350);
DISPLAY INVISIBLE (-6525 5350);
FORCEPROP 1 LAST BODY_TYPE PLUMBING
J 0
(-6525 5300);
DISPLAY 0.574468 (-6525 5300);
PAINT GREEN (-6525 5300);
DISPLAY INVISIBLE (-6525 5300);
FORCEPROP 1 LAST HDL_TAP TRUE
J 0
(-6200 5225);
DISPLAY 0.574468 (-6200 5225);
PAINT GREEN (-6200 5225);
DISPLAY INVISIBLE (-6200 5225);
FORCEPROP 1 LAST PATH I309
J 0
(-6527 5350);
DISPLAY 0.872340 (-6527 5350);
PAINT GREEN (-6527 5350);
DISPLAY INVISIBLE (-6527 5350);
FORCEADD TAP..6
(-6525 5150);
FORCEPROP 3 LASTPIN (-6475 5150) SIG_NAME GMI_CPU0_G2_CPU1_G0_TX_DP<9>
J 0
(-6465 5160);
DISPLAY 0.659574 (-6465 5160);
PAINT MONO (-6465 5160);
DISPLAY INVISIBLE (-6465 5160);
FORCEPROP 1 LASTPIN (-6475 5150) BN 9
J 0
(-6527 5158);
DISPLAY 0.489362 (-6527 5158);
PAINT MONO (-6527 5158);
FORCEPROP 2 LAST CDS_LIB standard
J 0
(-6525 5150);
DISPLAY INVISIBLE (-6525 5150);
FORCEPROP 1 LAST BODY_TYPE PLUMBING
J 0
(-6525 5100);
DISPLAY 0.574468 (-6525 5100);
PAINT GREEN (-6525 5100);
DISPLAY INVISIBLE (-6525 5100);
FORCEPROP 1 LAST HDL_TAP TRUE
J 0
(-6200 5025);
DISPLAY 0.574468 (-6200 5025);
PAINT GREEN (-6200 5025);
DISPLAY INVISIBLE (-6200 5025);
FORCEPROP 1 LAST PATH I310
J 0
(-6527 5150);
DISPLAY 0.872340 (-6527 5150);
PAINT GREEN (-6527 5150);
DISPLAY INVISIBLE (-6527 5150);
FORCEADD TAP..6
(-6525 5050);
FORCEPROP 3 LASTPIN (-6475 5050) SIG_NAME GMI_CPU0_G2_CPU1_G0_TX_DP<8>
J 0
(-6465 5060);
DISPLAY 0.659574 (-6465 5060);
PAINT MONO (-6465 5060);
DISPLAY INVISIBLE (-6465 5060);
FORCEPROP 1 LASTPIN (-6475 5050) BN 8
J 0
(-6527 5058);
DISPLAY 0.489362 (-6527 5058);
PAINT MONO (-6527 5058);
FORCEPROP 2 LAST CDS_LIB standard
J 0
(-6525 5050);
DISPLAY INVISIBLE (-6525 5050);
FORCEPROP 1 LAST BODY_TYPE PLUMBING
J 0
(-6525 5000);
DISPLAY 0.574468 (-6525 5000);
PAINT GREEN (-6525 5000);
DISPLAY INVISIBLE (-6525 5000);
FORCEPROP 1 LAST HDL_TAP TRUE
J 0
(-6200 4925);
DISPLAY 0.574468 (-6200 4925);
PAINT GREEN (-6200 4925);
DISPLAY INVISIBLE (-6200 4925);
FORCEPROP 1 LAST PATH I313
J 0
(-6527 5050);
DISPLAY 0.872340 (-6527 5050);
PAINT GREEN (-6527 5050);
DISPLAY INVISIBLE (-6527 5050);
FORCEADD TAP..6
(-6525 4950);
FORCEPROP 3 LASTPIN (-6475 4950) SIG_NAME GMI_CPU0_G2_CPU1_G0_TX_DP<7>
J 0
(-6465 4960);
DISPLAY 0.659574 (-6465 4960);
PAINT MONO (-6465 4960);
DISPLAY INVISIBLE (-6465 4960);
FORCEPROP 1 LASTPIN (-6475 4950) BN 7
J 0
(-6527 4958);
DISPLAY 0.489362 (-6527 4958);
PAINT MONO (-6527 4958);
FORCEPROP 2 LAST CDS_LIB standard
J 0
(-6525 4950);
DISPLAY INVISIBLE (-6525 4950);
FORCEPROP 1 LAST BODY_TYPE PLUMBING
J 0
(-6525 4900);
DISPLAY 0.574468 (-6525 4900);
PAINT GREEN (-6525 4900);
DISPLAY INVISIBLE (-6525 4900);
FORCEPROP 1 LAST HDL_TAP TRUE
J 0
(-6200 4825);
DISPLAY 0.574468 (-6200 4825);
PAINT GREEN (-6200 4825);
DISPLAY INVISIBLE (-6200 4825);
FORCEPROP 1 LAST PATH I314
J 0
(-6527 4950);
DISPLAY 0.872340 (-6527 4950);
PAINT GREEN (-6527 4950);
DISPLAY INVISIBLE (-6527 4950);
FORCEADD TAP..6
(-6525 4850);
FORCEPROP 3 LASTPIN (-6475 4850) SIG_NAME GMI_CPU0_G2_CPU1_G0_TX_DP<6>
J 0
(-6465 4860);
DISPLAY 0.659574 (-6465 4860);
PAINT MONO (-6465 4860);
DISPLAY INVISIBLE (-6465 4860);
FORCEPROP 1 LASTPIN (-6475 4850) BN 6
J 0
(-6527 4858);
DISPLAY 0.489362 (-6527 4858);
PAINT MONO (-6527 4858);
FORCEPROP 2 LAST CDS_LIB standard
J 0
(-6525 4850);
DISPLAY INVISIBLE (-6525 4850);
FORCEPROP 1 LAST BODY_TYPE PLUMBING
J 0
(-6525 4800);
DISPLAY 0.574468 (-6525 4800);
PAINT GREEN (-6525 4800);
DISPLAY INVISIBLE (-6525 4800);
FORCEPROP 1 LAST HDL_TAP TRUE
J 0
(-6200 4725);
DISPLAY 0.574468 (-6200 4725);
PAINT GREEN (-6200 4725);
DISPLAY INVISIBLE (-6200 4725);
FORCEPROP 1 LAST PATH I318
J 0
(-6527 4850);
DISPLAY 0.872340 (-6527 4850);
PAINT GREEN (-6527 4850);
DISPLAY INVISIBLE (-6527 4850);
FORCEADD TAP..6
(-6525 4750);
FORCEPROP 3 LASTPIN (-6475 4750) SIG_NAME GMI_CPU0_G2_CPU1_G0_TX_DP<5>
J 0
(-6465 4760);
DISPLAY 0.659574 (-6465 4760);
PAINT MONO (-6465 4760);
DISPLAY INVISIBLE (-6465 4760);
FORCEPROP 1 LASTPIN (-6475 4750) BN 5
J 0
(-6527 4758);
DISPLAY 0.489362 (-6527 4758);
PAINT MONO (-6527 4758);
FORCEPROP 2 LAST CDS_LIB standard
J 0
(-6525 4750);
DISPLAY INVISIBLE (-6525 4750);
FORCEPROP 1 LAST BODY_TYPE PLUMBING
J 0
(-6525 4700);
DISPLAY 0.574468 (-6525 4700);
PAINT GREEN (-6525 4700);
DISPLAY INVISIBLE (-6525 4700);
FORCEPROP 1 LAST HDL_TAP TRUE
J 0
(-6200 4625);
DISPLAY 0.574468 (-6200 4625);
PAINT GREEN (-6200 4625);
DISPLAY INVISIBLE (-6200 4625);
FORCEPROP 1 LAST PATH I319
J 0
(-6527 4750);
DISPLAY 0.872340 (-6527 4750);
PAINT GREEN (-6527 4750);
DISPLAY INVISIBLE (-6527 4750);
FORCEADD TAP..6
(-6525 4650);
FORCEPROP 3 LASTPIN (-6475 4650) SIG_NAME GMI_CPU0_G2_CPU1_G0_TX_DP<4>
J 0
(-6465 4660);
DISPLAY 0.659574 (-6465 4660);
PAINT MONO (-6465 4660);
DISPLAY INVISIBLE (-6465 4660);
FORCEPROP 1 LASTPIN (-6475 4650) BN 4
J 0
(-6527 4658);
DISPLAY 0.489362 (-6527 4658);
PAINT MONO (-6527 4658);
FORCEPROP 2 LAST CDS_LIB standard
J 0
(-6525 4650);
DISPLAY INVISIBLE (-6525 4650);
FORCEPROP 1 LAST BODY_TYPE PLUMBING
J 0
(-6525 4600);
DISPLAY 0.574468 (-6525 4600);
PAINT GREEN (-6525 4600);
DISPLAY INVISIBLE (-6525 4600);
FORCEPROP 1 LAST HDL_TAP TRUE
J 0
(-6200 4525);
DISPLAY 0.574468 (-6200 4525);
PAINT GREEN (-6200 4525);
DISPLAY INVISIBLE (-6200 4525);
FORCEPROP 1 LAST PATH I320
J 0
(-6527 4650);
DISPLAY 0.872340 (-6527 4650);
PAINT GREEN (-6527 4650);
DISPLAY INVISIBLE (-6527 4650);
FORCEADD TAP..6
(-6525 4550);
FORCEPROP 3 LASTPIN (-6475 4550) SIG_NAME GMI_CPU0_G2_CPU1_G0_TX_DP<3>
J 0
(-6465 4560);
DISPLAY 0.659574 (-6465 4560);
PAINT MONO (-6465 4560);
DISPLAY INVISIBLE (-6465 4560);
FORCEPROP 1 LASTPIN (-6475 4550) BN 3
J 0
(-6527 4558);
DISPLAY 0.489362 (-6527 4558);
PAINT MONO (-6527 4558);
FORCEPROP 2 LAST CDS_LIB standard
J 0
(-6525 4550);
DISPLAY INVISIBLE (-6525 4550);
FORCEPROP 1 LAST BODY_TYPE PLUMBING
J 0
(-6525 4500);
DISPLAY 0.574468 (-6525 4500);
PAINT GREEN (-6525 4500);
DISPLAY INVISIBLE (-6525 4500);
FORCEPROP 1 LAST HDL_TAP TRUE
J 0
(-6200 4425);
DISPLAY 0.574468 (-6200 4425);
PAINT GREEN (-6200 4425);
DISPLAY INVISIBLE (-6200 4425);
FORCEPROP 1 LAST PATH I323
J 0
(-6527 4550);
DISPLAY 0.872340 (-6527 4550);
PAINT GREEN (-6527 4550);
DISPLAY INVISIBLE (-6527 4550);
FORCEADD TAP..6
(-6525 4450);
FORCEPROP 3 LASTPIN (-6475 4450) SIG_NAME GMI_CPU0_G2_CPU1_G0_TX_DP<2>
J 0
(-6465 4460);
DISPLAY 0.659574 (-6465 4460);
PAINT MONO (-6465 4460);
DISPLAY INVISIBLE (-6465 4460);
FORCEPROP 1 LASTPIN (-6475 4450) BN 2
J 0
(-6527 4458);
DISPLAY 0.489362 (-6527 4458);
PAINT MONO (-6527 4458);
FORCEPROP 2 LAST CDS_LIB standard
J 0
(-6525 4450);
DISPLAY INVISIBLE (-6525 4450);
FORCEPROP 1 LAST BODY_TYPE PLUMBING
J 0
(-6525 4400);
DISPLAY 0.574468 (-6525 4400);
PAINT GREEN (-6525 4400);
DISPLAY INVISIBLE (-6525 4400);
FORCEPROP 1 LAST HDL_TAP TRUE
J 0
(-6200 4325);
DISPLAY 0.574468 (-6200 4325);
PAINT GREEN (-6200 4325);
DISPLAY INVISIBLE (-6200 4325);
FORCEPROP 1 LAST PATH I324
J 0
(-6527 4450);
DISPLAY 0.872340 (-6527 4450);
PAINT GREEN (-6527 4450);
DISPLAY INVISIBLE (-6527 4450);
FORCEADD TAP..6
(-6525 4250);
FORCEPROP 3 LASTPIN (-6475 4250) SIG_NAME GMI_CPU0_G2_CPU1_G0_TX_DP<0>
J 0
(-6465 4260);
DISPLAY 0.659574 (-6465 4260);
PAINT MONO (-6465 4260);
DISPLAY INVISIBLE (-6465 4260);
FORCEPROP 1 LASTPIN (-6475 4250) BN 0
J 0
(-6527 4258);
DISPLAY 0.489362 (-6527 4258);
PAINT MONO (-6527 4258);
FORCEPROP 2 LAST CDS_LIB standard
J 0
(-6525 4250);
DISPLAY INVISIBLE (-6525 4250);
FORCEPROP 1 LAST BODY_TYPE PLUMBING
J 0
(-6525 4200);
DISPLAY 0.574468 (-6525 4200);
PAINT GREEN (-6525 4200);
DISPLAY INVISIBLE (-6525 4200);
FORCEPROP 1 LAST HDL_TAP TRUE
J 0
(-6200 4125);
DISPLAY 0.574468 (-6200 4125);
PAINT GREEN (-6200 4125);
DISPLAY INVISIBLE (-6200 4125);
FORCEPROP 1 LAST PATH I328
J 0
(-6527 4250);
DISPLAY 0.872340 (-6527 4250);
PAINT GREEN (-6527 4250);
DISPLAY INVISIBLE (-6527 4250);
FORCEADD TAP..6
(-6525 4350);
FORCEPROP 3 LASTPIN (-6475 4350) SIG_NAME GMI_CPU0_G2_CPU1_G0_TX_DP<1>
J 0
(-6465 4360);
DISPLAY 0.659574 (-6465 4360);
PAINT MONO (-6465 4360);
DISPLAY INVISIBLE (-6465 4360);
FORCEPROP 1 LASTPIN (-6475 4350) BN 1
J 0
(-6527 4358);
DISPLAY 0.489362 (-6527 4358);
PAINT MONO (-6527 4358);
FORCEPROP 2 LAST CDS_LIB standard
J 0
(-6525 4350);
DISPLAY INVISIBLE (-6525 4350);
FORCEPROP 1 LAST BODY_TYPE PLUMBING
J 0
(-6525 4300);
DISPLAY 0.574468 (-6525 4300);
PAINT GREEN (-6525 4300);
DISPLAY INVISIBLE (-6525 4300);
FORCEPROP 1 LAST HDL_TAP TRUE
J 0
(-6200 4225);
DISPLAY 0.574468 (-6200 4225);
PAINT GREEN (-6200 4225);
DISPLAY INVISIBLE (-6200 4225);
FORCEPROP 1 LAST PATH I329
J 0
(-6527 4350);
DISPLAY 0.872340 (-6527 4350);
PAINT GREEN (-6527 4350);
DISPLAY INVISIBLE (-6527 4350);
FORCEADD OFFPAGE..1
(-7725 5975);
FORCEPROP 2 LAST $XR0 23 
J 0
(-7946 5975);
DISPLAY 0.638298 (-7946 5975);
PAINT MONO (-7946 5975);
FORCEPROP 2 LAST CDS_LIB standard
J 0
(-7725 5975);
DISPLAY INVISIBLE (-7725 5975);
FORCEPROP 1 LAST OFFPAGE TRUE
J 0
(-7400 5850);
DISPLAY 0.872340 (-7400 5850);
PAINT GREEN (-7400 5850);
DISPLAY INVISIBLE (-7400 5850);
FORCEPROP 1 LAST COMMENT_BODY TRUE
J 0
(-7600 5875);
DISPLAY 0.872340 (-7600 5875);
PAINT GREEN (-7600 5875);
DISPLAY INVISIBLE (-7600 5875);
FORCEPROP 2 LAST PATH I333
J 0
(-7925 6025);
DISPLAY 1.021277 (-7925 6025);
DISPLAY INVISIBLE (-7925 6025);
FORCEADD TAP..6
(-6500 3025);
FORCEPROP 3 LASTPIN (-6450 3025) SIG_NAME P5E_CPU1_G1_RX_DP<0>
J 0
(-6440 3035);
DISPLAY 0.659574 (-6440 3035);
PAINT MONO (-6440 3035);
DISPLAY INVISIBLE (-6440 3035);
FORCEPROP 1 LASTPIN (-6450 3025) BN 0
J 0
(-6502 3033);
DISPLAY 0.489362 (-6502 3033);
PAINT MONO (-6502 3033);
FORCEPROP 2 LAST CDS_LIB mstr_standard
J 0
(-6500 3025);
DISPLAY INVISIBLE (-6500 3025);
FORCEPROP 1 LAST BODY_TYPE PLUMBING
J 0
(-6500 2975);
DISPLAY 0.574468 (-6500 2975);
PAINT GREEN (-6500 2975);
DISPLAY INVISIBLE (-6500 2975);
FORCEPROP 1 LAST HDL_TAP TRUE
J 0
(-6175 2900);
DISPLAY 0.574468 (-6175 2900);
PAINT GREEN (-6175 2900);
DISPLAY INVISIBLE (-6175 2900);
FORCEPROP 1 LAST PATH I334
J 0
(-6502 3025);
DISPLAY 0.872340 (-6502 3025);
PAINT GREEN (-6502 3025);
DISPLAY INVISIBLE (-6502 3025);
FORCEADD TAP..6
(-6500 2925);
FORCEPROP 3 LASTPIN (-6450 2925) SIG_NAME P5E_CPU1_G1_RX_DP<1>
J 0
(-6440 2935);
DISPLAY 0.659574 (-6440 2935);
PAINT MONO (-6440 2935);
DISPLAY INVISIBLE (-6440 2935);
FORCEPROP 1 LASTPIN (-6450 2925) BN 1
J 0
(-6502 2933);
DISPLAY 0.489362 (-6502 2933);
PAINT MONO (-6502 2933);
FORCEPROP 2 LAST CDS_LIB mstr_standard
J 0
(-6500 2925);
DISPLAY INVISIBLE (-6500 2925);
FORCEPROP 1 LAST BODY_TYPE PLUMBING
J 0
(-6500 2875);
DISPLAY 0.574468 (-6500 2875);
PAINT GREEN (-6500 2875);
DISPLAY INVISIBLE (-6500 2875);
FORCEPROP 1 LAST HDL_TAP TRUE
J 0
(-6175 2800);
DISPLAY 0.574468 (-6175 2800);
PAINT GREEN (-6175 2800);
DISPLAY INVISIBLE (-6175 2800);
FORCEPROP 1 LAST PATH I335
J 0
(-6502 2925);
DISPLAY 0.872340 (-6502 2925);
PAINT GREEN (-6502 2925);
DISPLAY INVISIBLE (-6502 2925);
FORCEADD TAP..6
(-6500 2825);
FORCEPROP 3 LASTPIN (-6450 2825) SIG_NAME P5E_CPU1_G1_RX_DP<2>
J 0
(-6440 2835);
DISPLAY 0.659574 (-6440 2835);
PAINT MONO (-6440 2835);
DISPLAY INVISIBLE (-6440 2835);
FORCEPROP 1 LASTPIN (-6450 2825) BN 2
J 0
(-6502 2833);
DISPLAY 0.489362 (-6502 2833);
PAINT MONO (-6502 2833);
FORCEPROP 2 LAST CDS_LIB mstr_standard
J 0
(-6500 2825);
DISPLAY INVISIBLE (-6500 2825);
FORCEPROP 1 LAST BODY_TYPE PLUMBING
J 0
(-6500 2775);
DISPLAY 0.574468 (-6500 2775);
PAINT GREEN (-6500 2775);
DISPLAY INVISIBLE (-6500 2775);
FORCEPROP 1 LAST HDL_TAP TRUE
J 0
(-6175 2700);
DISPLAY 0.574468 (-6175 2700);
PAINT GREEN (-6175 2700);
DISPLAY INVISIBLE (-6175 2700);
FORCEPROP 1 LAST PATH I336
J 0
(-6502 2825);
DISPLAY 0.872340 (-6502 2825);
PAINT GREEN (-6502 2825);
DISPLAY INVISIBLE (-6502 2825);
FORCEADD TAP..6
(-6500 2725);
FORCEPROP 3 LASTPIN (-6450 2725) SIG_NAME P5E_CPU1_G1_RX_DP<3>
J 0
(-6440 2735);
DISPLAY 0.659574 (-6440 2735);
PAINT MONO (-6440 2735);
DISPLAY INVISIBLE (-6440 2735);
FORCEPROP 1 LASTPIN (-6450 2725) BN 3
J 0
(-6502 2733);
DISPLAY 0.489362 (-6502 2733);
PAINT MONO (-6502 2733);
FORCEPROP 2 LAST CDS_LIB standard
J 0
(-6500 2725);
DISPLAY INVISIBLE (-6500 2725);
FORCEPROP 1 LAST BODY_TYPE PLUMBING
J 0
(-6500 2675);
DISPLAY 0.574468 (-6500 2675);
PAINT GREEN (-6500 2675);
DISPLAY INVISIBLE (-6500 2675);
FORCEPROP 1 LAST HDL_TAP TRUE
J 0
(-6175 2600);
DISPLAY 0.574468 (-6175 2600);
PAINT GREEN (-6175 2600);
DISPLAY INVISIBLE (-6175 2600);
FORCEPROP 1 LAST PATH I339
J 0
(-6502 2725);
DISPLAY 0.872340 (-6502 2725);
PAINT GREEN (-6502 2725);
DISPLAY INVISIBLE (-6502 2725);
FORCEADD TAP..6
(-6500 2625);
FORCEPROP 3 LASTPIN (-6450 2625) SIG_NAME P5E_CPU1_G1_RX_DP<4>
J 0
(-6440 2635);
DISPLAY 0.659574 (-6440 2635);
PAINT MONO (-6440 2635);
DISPLAY INVISIBLE (-6440 2635);
FORCEPROP 1 LASTPIN (-6450 2625) BN 4
J 0
(-6502 2633);
DISPLAY 0.489362 (-6502 2633);
PAINT MONO (-6502 2633);
FORCEPROP 2 LAST CDS_LIB standard
J 0
(-6500 2625);
DISPLAY INVISIBLE (-6500 2625);
FORCEPROP 1 LAST BODY_TYPE PLUMBING
J 0
(-6500 2575);
DISPLAY 0.574468 (-6500 2575);
PAINT GREEN (-6500 2575);
DISPLAY INVISIBLE (-6500 2575);
FORCEPROP 1 LAST HDL_TAP TRUE
J 0
(-6175 2500);
DISPLAY 0.574468 (-6175 2500);
PAINT GREEN (-6175 2500);
DISPLAY INVISIBLE (-6175 2500);
FORCEPROP 1 LAST PATH I340
J 0
(-6502 2625);
DISPLAY 0.872340 (-6502 2625);
PAINT GREEN (-6502 2625);
DISPLAY INVISIBLE (-6502 2625);
FORCEADD TAP..6
(-6500 2525);
FORCEPROP 3 LASTPIN (-6450 2525) SIG_NAME P5E_CPU1_G1_RX_DP<5>
J 0
(-6440 2535);
DISPLAY 0.659574 (-6440 2535);
PAINT MONO (-6440 2535);
DISPLAY INVISIBLE (-6440 2535);
FORCEPROP 1 LASTPIN (-6450 2525) BN 5
J 0
(-6502 2533);
DISPLAY 0.489362 (-6502 2533);
PAINT MONO (-6502 2533);
FORCEPROP 2 LAST CDS_LIB standard
J 0
(-6500 2525);
DISPLAY INVISIBLE (-6500 2525);
FORCEPROP 1 LAST BODY_TYPE PLUMBING
J 0
(-6500 2475);
DISPLAY 0.574468 (-6500 2475);
PAINT GREEN (-6500 2475);
DISPLAY INVISIBLE (-6500 2475);
FORCEPROP 1 LAST HDL_TAP TRUE
J 0
(-6175 2400);
DISPLAY 0.574468 (-6175 2400);
PAINT GREEN (-6175 2400);
DISPLAY INVISIBLE (-6175 2400);
FORCEPROP 1 LAST PATH I344
J 0
(-6502 2525);
DISPLAY 0.872340 (-6502 2525);
PAINT GREEN (-6502 2525);
DISPLAY INVISIBLE (-6502 2525);
FORCEADD TAP..6
(-6500 2425);
FORCEPROP 3 LASTPIN (-6450 2425) SIG_NAME P5E_CPU1_G1_RX_DP<6>
J 0
(-6440 2435);
DISPLAY 0.659574 (-6440 2435);
PAINT MONO (-6440 2435);
DISPLAY INVISIBLE (-6440 2435);
FORCEPROP 1 LASTPIN (-6450 2425) BN 6
J 0
(-6502 2433);
DISPLAY 0.489362 (-6502 2433);
PAINT MONO (-6502 2433);
FORCEPROP 2 LAST CDS_LIB standard
J 0
(-6500 2425);
DISPLAY INVISIBLE (-6500 2425);
FORCEPROP 1 LAST BODY_TYPE PLUMBING
J 0
(-6500 2375);
DISPLAY 0.574468 (-6500 2375);
PAINT GREEN (-6500 2375);
DISPLAY INVISIBLE (-6500 2375);
FORCEPROP 1 LAST HDL_TAP TRUE
J 0
(-6175 2300);
DISPLAY 0.574468 (-6175 2300);
PAINT GREEN (-6175 2300);
DISPLAY INVISIBLE (-6175 2300);
FORCEPROP 1 LAST PATH I345
J 0
(-6502 2425);
DISPLAY 0.872340 (-6502 2425);
PAINT GREEN (-6502 2425);
DISPLAY INVISIBLE (-6502 2425);
FORCEADD TAP..6
(-6500 2325);
FORCEPROP 3 LASTPIN (-6450 2325) SIG_NAME P5E_CPU1_G1_RX_DP<7>
J 0
(-6440 2335);
DISPLAY 0.659574 (-6440 2335);
PAINT MONO (-6440 2335);
DISPLAY INVISIBLE (-6440 2335);
FORCEPROP 1 LASTPIN (-6450 2325) BN 7
J 0
(-6502 2333);
DISPLAY 0.489362 (-6502 2333);
PAINT MONO (-6502 2333);
FORCEPROP 2 LAST CDS_LIB standard
J 0
(-6500 2325);
DISPLAY INVISIBLE (-6500 2325);
FORCEPROP 1 LAST BODY_TYPE PLUMBING
J 0
(-6500 2275);
DISPLAY 0.574468 (-6500 2275);
PAINT GREEN (-6500 2275);
DISPLAY INVISIBLE (-6500 2275);
FORCEPROP 1 LAST HDL_TAP TRUE
J 0
(-6175 2200);
DISPLAY 0.574468 (-6175 2200);
PAINT GREEN (-6175 2200);
DISPLAY INVISIBLE (-6175 2200);
FORCEPROP 1 LAST PATH I346
J 0
(-6502 2325);
DISPLAY 0.872340 (-6502 2325);
PAINT GREEN (-6502 2325);
DISPLAY INVISIBLE (-6502 2325);
FORCEADD TAP..6
(-6500 2225);
FORCEPROP 3 LASTPIN (-6450 2225) SIG_NAME P5E_CPU1_G1_RX_DP<8>
J 0
(-6440 2235);
DISPLAY 0.659574 (-6440 2235);
PAINT MONO (-6440 2235);
DISPLAY INVISIBLE (-6440 2235);
FORCEPROP 1 LASTPIN (-6450 2225) BN 8
J 0
(-6502 2233);
DISPLAY 0.489362 (-6502 2233);
PAINT MONO (-6502 2233);
FORCEPROP 2 LAST CDS_LIB standard
J 0
(-6500 2225);
DISPLAY INVISIBLE (-6500 2225);
FORCEPROP 1 LAST BODY_TYPE PLUMBING
J 0
(-6500 2175);
DISPLAY 0.574468 (-6500 2175);
PAINT GREEN (-6500 2175);
DISPLAY INVISIBLE (-6500 2175);
FORCEPROP 1 LAST HDL_TAP TRUE
J 0
(-6175 2100);
DISPLAY 0.574468 (-6175 2100);
PAINT GREEN (-6175 2100);
DISPLAY INVISIBLE (-6175 2100);
FORCEPROP 1 LAST PATH I349
J 0
(-6502 2225);
DISPLAY 0.872340 (-6502 2225);
PAINT GREEN (-6502 2225);
DISPLAY INVISIBLE (-6502 2225);
FORCEADD TAP..6
(-6500 2125);
FORCEPROP 3 LASTPIN (-6450 2125) SIG_NAME P5E_CPU1_G1_RX_DP<9>
J 0
(-6440 2135);
DISPLAY 0.659574 (-6440 2135);
PAINT MONO (-6440 2135);
DISPLAY INVISIBLE (-6440 2135);
FORCEPROP 1 LASTPIN (-6450 2125) BN 9
J 0
(-6502 2133);
DISPLAY 0.489362 (-6502 2133);
PAINT MONO (-6502 2133);
FORCEPROP 2 LAST CDS_LIB standard
J 0
(-6500 2125);
DISPLAY INVISIBLE (-6500 2125);
FORCEPROP 1 LAST BODY_TYPE PLUMBING
J 0
(-6500 2075);
DISPLAY 0.574468 (-6500 2075);
PAINT GREEN (-6500 2075);
DISPLAY INVISIBLE (-6500 2075);
FORCEPROP 1 LAST HDL_TAP TRUE
J 0
(-6175 2000);
DISPLAY 0.574468 (-6175 2000);
PAINT GREEN (-6175 2000);
DISPLAY INVISIBLE (-6175 2000);
FORCEPROP 1 LAST PATH I350
J 0
(-6502 2125);
DISPLAY 0.872340 (-6502 2125);
PAINT GREEN (-6502 2125);
DISPLAY INVISIBLE (-6502 2125);
FORCEADD OFFPAGE..1
(-7600 3250);
FORCEPROP 2 LASTPIN (-7550 3250) SIG_NAME P5E_CPU1_G1_RX_DP<15:0>
J 0
(-7535 3260);
DISPLAY 0.489362 (-7535 3260);
FORCEPROP 2 LAST $XR0 137 
J 0
(-7852 3250);
DISPLAY 0.638298 (-7852 3250);
PAINT MONO (-7852 3250);
FORCEPROP 2 LAST CDS_LIB standard
J 0
(-7600 3250);
DISPLAY INVISIBLE (-7600 3250);
FORCEPROP 1 LAST OFFPAGE TRUE
J 0
(-7275 3125);
DISPLAY 0.872340 (-7275 3125);
PAINT GREEN (-7275 3125);
DISPLAY INVISIBLE (-7275 3125);
FORCEPROP 1 LAST COMMENT_BODY TRUE
J 0
(-7475 3150);
DISPLAY 0.872340 (-7475 3150);
PAINT GREEN (-7475 3150);
DISPLAY INVISIBLE (-7475 3150);
FORCEPROP 2 LAST PATH I355
J 0
(-7800 3300);
DISPLAY 1.021277 (-7800 3300);
DISPLAY INVISIBLE (-7800 3300);
FORCEADD TAP..6
(-6500 2025);
FORCEPROP 3 LASTPIN (-6450 2025) SIG_NAME P5E_CPU1_G1_RX_DP<10>
J 0
(-6440 2035);
DISPLAY 0.659574 (-6440 2035);
PAINT MONO (-6440 2035);
DISPLAY INVISIBLE (-6440 2035);
FORCEPROP 1 LASTPIN (-6450 2025) BN 10
J 0
(-6502 2033);
DISPLAY 0.489362 (-6502 2033);
PAINT MONO (-6502 2033);
FORCEPROP 2 LAST CDS_LIB standard
J 0
(-6500 2025);
DISPLAY INVISIBLE (-6500 2025);
FORCEPROP 1 LAST BODY_TYPE PLUMBING
J 0
(-6500 1975);
DISPLAY 0.574468 (-6500 1975);
PAINT GREEN (-6500 1975);
DISPLAY INVISIBLE (-6500 1975);
FORCEPROP 1 LAST HDL_TAP TRUE
J 0
(-6175 1900);
DISPLAY 0.574468 (-6175 1900);
PAINT GREEN (-6175 1900);
DISPLAY INVISIBLE (-6175 1900);
FORCEPROP 1 LAST PATH I356
J 0
(-6502 2025);
DISPLAY 0.872340 (-6502 2025);
PAINT GREEN (-6502 2025);
DISPLAY INVISIBLE (-6502 2025);
FORCEADD TAP..6
(-6500 1925);
FORCEPROP 3 LASTPIN (-6450 1925) SIG_NAME P5E_CPU1_G1_RX_DP<11>
J 0
(-6440 1935);
DISPLAY 0.659574 (-6440 1935);
PAINT MONO (-6440 1935);
DISPLAY INVISIBLE (-6440 1935);
FORCEPROP 1 LASTPIN (-6450 1925) BN 11
J 0
(-6502 1933);
DISPLAY 0.489362 (-6502 1933);
PAINT MONO (-6502 1933);
FORCEPROP 2 LAST CDS_LIB standard
J 0
(-6500 1925);
DISPLAY INVISIBLE (-6500 1925);
FORCEPROP 1 LAST BODY_TYPE PLUMBING
J 0
(-6500 1875);
DISPLAY 0.574468 (-6500 1875);
PAINT GREEN (-6500 1875);
DISPLAY INVISIBLE (-6500 1875);
FORCEPROP 1 LAST HDL_TAP TRUE
J 0
(-6175 1800);
DISPLAY 0.574468 (-6175 1800);
PAINT GREEN (-6175 1800);
DISPLAY INVISIBLE (-6175 1800);
FORCEPROP 1 LAST PATH I357
J 0
(-6502 1925);
DISPLAY 0.872340 (-6502 1925);
PAINT GREEN (-6502 1925);
DISPLAY INVISIBLE (-6502 1925);
FORCEADD TAP..6
(-6500 1825);
FORCEPROP 3 LASTPIN (-6450 1825) SIG_NAME P5E_CPU1_G1_RX_DP<12>
J 0
(-6440 1835);
DISPLAY 0.659574 (-6440 1835);
PAINT MONO (-6440 1835);
DISPLAY INVISIBLE (-6440 1835);
FORCEPROP 1 LASTPIN (-6450 1825) BN 12
J 0
(-6502 1833);
DISPLAY 0.489362 (-6502 1833);
PAINT MONO (-6502 1833);
FORCEPROP 2 LAST CDS_LIB standard
J 0
(-6500 1825);
DISPLAY INVISIBLE (-6500 1825);
FORCEPROP 1 LAST BODY_TYPE PLUMBING
J 0
(-6500 1775);
DISPLAY 0.574468 (-6500 1775);
PAINT GREEN (-6500 1775);
DISPLAY INVISIBLE (-6500 1775);
FORCEPROP 1 LAST HDL_TAP TRUE
J 0
(-6175 1700);
DISPLAY 0.574468 (-6175 1700);
PAINT GREEN (-6175 1700);
DISPLAY INVISIBLE (-6175 1700);
FORCEPROP 1 LAST PATH I358
J 0
(-6502 1825);
DISPLAY 0.872340 (-6502 1825);
PAINT GREEN (-6502 1825);
DISPLAY INVISIBLE (-6502 1825);
FORCEADD TAP..6
(-6500 1725);
FORCEPROP 3 LASTPIN (-6450 1725) SIG_NAME P5E_CPU1_G1_RX_DP<13>
J 0
(-6440 1735);
DISPLAY 0.659574 (-6440 1735);
PAINT MONO (-6440 1735);
DISPLAY INVISIBLE (-6440 1735);
FORCEPROP 1 LASTPIN (-6450 1725) BN 13
J 0
(-6502 1733);
DISPLAY 0.489362 (-6502 1733);
PAINT MONO (-6502 1733);
FORCEPROP 2 LAST CDS_LIB standard
J 0
(-6500 1725);
DISPLAY INVISIBLE (-6500 1725);
FORCEPROP 1 LAST BODY_TYPE PLUMBING
J 0
(-6500 1675);
DISPLAY 0.574468 (-6500 1675);
PAINT GREEN (-6500 1675);
DISPLAY INVISIBLE (-6500 1675);
FORCEPROP 1 LAST HDL_TAP TRUE
J 0
(-6175 1600);
DISPLAY 0.574468 (-6175 1600);
PAINT GREEN (-6175 1600);
DISPLAY INVISIBLE (-6175 1600);
FORCEPROP 1 LAST PATH I361
J 0
(-6502 1725);
DISPLAY 0.872340 (-6502 1725);
PAINT GREEN (-6502 1725);
DISPLAY INVISIBLE (-6502 1725);
FORCEADD TAP..6
(-6500 1625);
FORCEPROP 3 LASTPIN (-6450 1625) SIG_NAME P5E_CPU1_G1_RX_DP<14>
J 0
(-6440 1635);
DISPLAY 0.659574 (-6440 1635);
PAINT MONO (-6440 1635);
DISPLAY INVISIBLE (-6440 1635);
FORCEPROP 1 LASTPIN (-6450 1625) BN 14
J 0
(-6502 1633);
DISPLAY 0.489362 (-6502 1633);
PAINT MONO (-6502 1633);
FORCEPROP 2 LAST CDS_LIB standard
J 0
(-6500 1625);
DISPLAY INVISIBLE (-6500 1625);
FORCEPROP 1 LAST BODY_TYPE PLUMBING
J 0
(-6500 1575);
DISPLAY 0.574468 (-6500 1575);
PAINT GREEN (-6500 1575);
DISPLAY INVISIBLE (-6500 1575);
FORCEPROP 1 LAST HDL_TAP TRUE
J 0
(-6175 1500);
DISPLAY 0.574468 (-6175 1500);
PAINT GREEN (-6175 1500);
DISPLAY INVISIBLE (-6175 1500);
FORCEPROP 1 LAST PATH I362
J 0
(-6502 1625);
DISPLAY 0.872340 (-6502 1625);
PAINT GREEN (-6502 1625);
DISPLAY INVISIBLE (-6502 1625);
FORCEADD TAP..6
(-6500 1525);
FORCEPROP 3 LASTPIN (-6450 1525) SIG_NAME P5E_CPU1_G1_RX_DP<15>
J 0
(-6440 1535);
DISPLAY 0.659574 (-6440 1535);
PAINT MONO (-6440 1535);
DISPLAY INVISIBLE (-6440 1535);
FORCEPROP 1 LASTPIN (-6450 1525) BN 15
J 0
(-6502 1533);
DISPLAY 0.489362 (-6502 1533);
PAINT MONO (-6502 1533);
FORCEPROP 2 LAST CDS_LIB standard
J 0
(-6500 1525);
DISPLAY INVISIBLE (-6500 1525);
FORCEPROP 1 LAST BODY_TYPE PLUMBING
J 0
(-6500 1475);
DISPLAY 0.574468 (-6500 1475);
PAINT GREEN (-6500 1475);
DISPLAY INVISIBLE (-6500 1475);
FORCEPROP 1 LAST HDL_TAP TRUE
J 0
(-6175 1400);
DISPLAY 0.574468 (-6175 1400);
PAINT GREEN (-6175 1400);
DISPLAY INVISIBLE (-6175 1400);
FORCEPROP 1 LAST PATH I366
J 0
(-6502 1525);
DISPLAY 0.872340 (-6502 1525);
PAINT GREEN (-6502 1525);
DISPLAY INVISIBLE (-6502 1525);
FORCEADD OFFPAGE..2
(-1825 5925);
FORCEPROP 2 LAST $XR0 23 
J 0
(-1636 5925);
DISPLAY 0.638298 (-1636 5925);
PAINT MONO (-1636 5925);
FORCEPROP 2 LAST CDS_LIB standard
J 0
(-1825 5925);
DISPLAY INVISIBLE (-1825 5925);
FORCEPROP 1 LAST OFFPAGE TRUE
J 0
(-1500 5800);
DISPLAY 0.872340 (-1500 5800);
PAINT GREEN (-1500 5800);
DISPLAY INVISIBLE (-1500 5800);
FORCEPROP 1 LAST COMMENT_BODY TRUE
J 0
(-1870 5830);
DISPLAY 0.872340 (-1870 5830);
PAINT GREEN (-1870 5830);
DISPLAY INVISIBLE (-1870 5830);
FORCEPROP 2 LAST PATH I436
J 0
(-1625 5975);
DISPLAY 1.021277 (-1625 5975);
DISPLAY INVISIBLE (-1625 5975);
FORCEADD TAP..6
R 2
(-2950 5700);
FORCEPROP 3 LASTPIN (-3000 5700) SIG_NAME GMI_CPU1_G0_CPU0_G2_TX_DN<15>
J 0
(-2990 5710);
DISPLAY 0.659574 (-2990 5710);
PAINT MONO (-2990 5710);
DISPLAY INVISIBLE (-2990 5710);
FORCEPROP 1 LASTPIN (-3000 5700) BN 15
J 2
(-2948 5708);
DISPLAY 0.489362 (-2948 5708);
PAINT MONO (-2948 5708);
FORCEPROP 2 LAST ROOM RISER1
J 0
(-3450 5750);
DISPLAY 0.829787 (-3450 5750);
PAINT RED (-3450 5750);
DISPLAY INVISIBLE (-3450 5750);
FORCEPROP 2 LAST BOM_COST IO_SLOT
J 0
(-3450 5800);
DISPLAY 0.829787 (-3450 5800);
DISPLAY INVISIBLE (-3450 5800);
FORCEPROP 2 LAST CDS_LIB mstr_standard
J 0
(-2950 5700);
DISPLAY INVISIBLE (-2950 5700);
FORCEPROP 1 LAST BODY_TYPE PLUMBING
J 2
(-2950 5650);
DISPLAY 0.702128 (-2950 5650);
PAINT GREEN (-2950 5650);
DISPLAY INVISIBLE (-2950 5650);
FORCEPROP 1 LAST HDL_TAP TRUE
J 2
(-3275 5575);
DISPLAY 0.702128 (-3275 5575);
PAINT GREEN (-3275 5575);
DISPLAY INVISIBLE (-3275 5575);
FORCEPROP 1 LAST PATH I437
J 2
(-2948 5700);
DISPLAY 0.872340 (-2948 5700);
PAINT GREEN (-2948 5700);
DISPLAY INVISIBLE (-2948 5700);
FORCEADD TAP..6
R 2
(-2950 5600);
FORCEPROP 3 LASTPIN (-3000 5600) SIG_NAME GMI_CPU1_G0_CPU0_G2_TX_DN<14>
J 0
(-2990 5610);
DISPLAY 0.659574 (-2990 5610);
PAINT MONO (-2990 5610);
DISPLAY INVISIBLE (-2990 5610);
FORCEPROP 1 LASTPIN (-3000 5600) BN 14
J 2
(-2948 5608);
DISPLAY 0.489362 (-2948 5608);
PAINT MONO (-2948 5608);
FORCEPROP 2 LAST ROOM RISER1
J 0
(-3450 5650);
DISPLAY 0.829787 (-3450 5650);
PAINT RED (-3450 5650);
DISPLAY INVISIBLE (-3450 5650);
FORCEPROP 2 LAST CDS_LIB mstr_standard
J 0
(-2950 5600);
DISPLAY INVISIBLE (-2950 5600);
FORCEPROP 2 LAST BOM_COST IO_SLOT
J 0
(-3450 5700);
DISPLAY 0.829787 (-3450 5700);
DISPLAY INVISIBLE (-3450 5700);
FORCEPROP 1 LAST BODY_TYPE PLUMBING
J 2
(-2950 5550);
DISPLAY 0.702128 (-2950 5550);
PAINT GREEN (-2950 5550);
DISPLAY INVISIBLE (-2950 5550);
FORCEPROP 1 LAST HDL_TAP TRUE
J 2
(-3275 5475);
DISPLAY 0.702128 (-3275 5475);
PAINT GREEN (-3275 5475);
DISPLAY INVISIBLE (-3275 5475);
FORCEPROP 1 LAST PATH I438
J 2
(-2948 5600);
DISPLAY 0.872340 (-2948 5600);
PAINT GREEN (-2948 5600);
DISPLAY INVISIBLE (-2948 5600);
FORCEADD TAP..6
R 2
(-2950 5500);
FORCEPROP 3 LASTPIN (-3000 5500) SIG_NAME GMI_CPU1_G0_CPU0_G2_TX_DN<13>
J 0
(-2990 5510);
DISPLAY 0.659574 (-2990 5510);
PAINT MONO (-2990 5510);
DISPLAY INVISIBLE (-2990 5510);
FORCEPROP 1 LASTPIN (-3000 5500) BN 13
J 2
(-2948 5508);
DISPLAY 0.489362 (-2948 5508);
PAINT MONO (-2948 5508);
FORCEPROP 2 LAST ROOM RISER1
J 0
(-3450 5550);
DISPLAY 0.829787 (-3450 5550);
PAINT RED (-3450 5550);
DISPLAY INVISIBLE (-3450 5550);
FORCEPROP 2 LAST CDS_LIB standard
J 0
(-2950 5500);
DISPLAY INVISIBLE (-2950 5500);
FORCEPROP 2 LAST BOM_COST IO_SLOT
J 0
(-3450 5600);
DISPLAY 0.829787 (-3450 5600);
DISPLAY INVISIBLE (-3450 5600);
FORCEPROP 1 LAST BODY_TYPE PLUMBING
J 2
(-2950 5450);
DISPLAY 0.702128 (-2950 5450);
PAINT GREEN (-2950 5450);
DISPLAY INVISIBLE (-2950 5450);
FORCEPROP 1 LAST HDL_TAP TRUE
J 2
(-3275 5375);
DISPLAY 0.702128 (-3275 5375);
PAINT GREEN (-3275 5375);
DISPLAY INVISIBLE (-3275 5375);
FORCEPROP 1 LAST PATH I439
J 2
(-2948 5500);
DISPLAY 0.872340 (-2948 5500);
PAINT GREEN (-2948 5500);
DISPLAY INVISIBLE (-2948 5500);
FORCEADD TAP..6
R 2
(-2950 5400);
FORCEPROP 3 LASTPIN (-3000 5400) SIG_NAME GMI_CPU1_G0_CPU0_G2_TX_DN<12>
J 0
(-2990 5410);
DISPLAY 0.659574 (-2990 5410);
PAINT MONO (-2990 5410);
DISPLAY INVISIBLE (-2990 5410);
FORCEPROP 1 LASTPIN (-3000 5400) BN 12
J 2
(-2948 5408);
DISPLAY 0.489362 (-2948 5408);
PAINT MONO (-2948 5408);
FORCEPROP 2 LAST ROOM RISER1
J 0
(-3450 5450);
DISPLAY 0.829787 (-3450 5450);
PAINT RED (-3450 5450);
DISPLAY INVISIBLE (-3450 5450);
FORCEPROP 2 LAST CDS_LIB standard
J 0
(-2950 5400);
DISPLAY INVISIBLE (-2950 5400);
FORCEPROP 2 LAST BOM_COST IO_SLOT
J 0
(-3450 5500);
DISPLAY 0.829787 (-3450 5500);
DISPLAY INVISIBLE (-3450 5500);
FORCEPROP 1 LAST BODY_TYPE PLUMBING
J 2
(-2950 5350);
DISPLAY 0.702128 (-2950 5350);
PAINT GREEN (-2950 5350);
DISPLAY INVISIBLE (-2950 5350);
FORCEPROP 1 LAST HDL_TAP TRUE
J 2
(-3275 5275);
DISPLAY 0.702128 (-3275 5275);
PAINT GREEN (-3275 5275);
DISPLAY INVISIBLE (-3275 5275);
FORCEPROP 1 LAST PATH I440
J 2
(-2948 5400);
DISPLAY 0.872340 (-2948 5400);
PAINT GREEN (-2948 5400);
DISPLAY INVISIBLE (-2948 5400);
FORCEADD TAP..6
R 2
(-2950 5300);
FORCEPROP 3 LASTPIN (-3000 5300) SIG_NAME GMI_CPU1_G0_CPU0_G2_TX_DN<11>
J 0
(-2990 5310);
DISPLAY 0.659574 (-2990 5310);
PAINT MONO (-2990 5310);
DISPLAY INVISIBLE (-2990 5310);
FORCEPROP 1 LASTPIN (-3000 5300) BN 11
J 2
(-2948 5308);
DISPLAY 0.489362 (-2948 5308);
PAINT MONO (-2948 5308);
FORCEPROP 2 LAST ROOM RISER1
J 0
(-3450 5350);
DISPLAY 0.829787 (-3450 5350);
PAINT RED (-3450 5350);
DISPLAY INVISIBLE (-3450 5350);
FORCEPROP 2 LAST CDS_LIB standard
J 0
(-2950 5300);
DISPLAY INVISIBLE (-2950 5300);
FORCEPROP 2 LAST BOM_COST IO_SLOT
J 0
(-3450 5400);
DISPLAY 0.829787 (-3450 5400);
DISPLAY INVISIBLE (-3450 5400);
FORCEPROP 1 LAST BODY_TYPE PLUMBING
J 2
(-2950 5250);
DISPLAY 0.702128 (-2950 5250);
PAINT GREEN (-2950 5250);
DISPLAY INVISIBLE (-2950 5250);
FORCEPROP 1 LAST HDL_TAP TRUE
J 2
(-3275 5175);
DISPLAY 0.702128 (-3275 5175);
PAINT GREEN (-3275 5175);
DISPLAY INVISIBLE (-3275 5175);
FORCEPROP 1 LAST PATH I441
J 2
(-2948 5300);
DISPLAY 0.872340 (-2948 5300);
PAINT GREEN (-2948 5300);
DISPLAY INVISIBLE (-2948 5300);
FORCEADD TAP..6
R 2
(-2950 5200);
FORCEPROP 3 LASTPIN (-3000 5200) SIG_NAME GMI_CPU1_G0_CPU0_G2_TX_DN<10>
J 0
(-2990 5210);
DISPLAY 0.659574 (-2990 5210);
PAINT MONO (-2990 5210);
DISPLAY INVISIBLE (-2990 5210);
FORCEPROP 1 LASTPIN (-3000 5200) BN 10
J 2
(-2948 5208);
DISPLAY 0.489362 (-2948 5208);
PAINT MONO (-2948 5208);
FORCEPROP 2 LAST ROOM RISER1
J 0
(-3450 5250);
DISPLAY 0.829787 (-3450 5250);
PAINT RED (-3450 5250);
DISPLAY INVISIBLE (-3450 5250);
FORCEPROP 2 LAST CDS_LIB standard
J 0
(-2950 5200);
DISPLAY INVISIBLE (-2950 5200);
FORCEPROP 2 LAST BOM_COST IO_SLOT
J 0
(-3450 5300);
DISPLAY 0.829787 (-3450 5300);
DISPLAY INVISIBLE (-3450 5300);
FORCEPROP 1 LAST BODY_TYPE PLUMBING
J 2
(-2950 5150);
DISPLAY 0.702128 (-2950 5150);
PAINT GREEN (-2950 5150);
DISPLAY INVISIBLE (-2950 5150);
FORCEPROP 1 LAST HDL_TAP TRUE
J 2
(-3275 5075);
DISPLAY 0.702128 (-3275 5075);
PAINT GREEN (-3275 5075);
DISPLAY INVISIBLE (-3275 5075);
FORCEPROP 1 LAST PATH I442
J 2
(-2948 5200);
DISPLAY 0.872340 (-2948 5200);
PAINT GREEN (-2948 5200);
DISPLAY INVISIBLE (-2948 5200);
FORCEADD TAP..6
R 2
(-2950 5100);
FORCEPROP 3 LASTPIN (-3000 5100) SIG_NAME GMI_CPU1_G0_CPU0_G2_TX_DN<9>
J 0
(-2990 5110);
DISPLAY 0.659574 (-2990 5110);
PAINT MONO (-2990 5110);
DISPLAY INVISIBLE (-2990 5110);
FORCEPROP 1 LASTPIN (-3000 5100) BN 9
J 2
(-2948 5108);
DISPLAY 0.489362 (-2948 5108);
PAINT MONO (-2948 5108);
FORCEPROP 2 LAST ROOM RISER1
J 0
(-3450 5150);
DISPLAY 0.829787 (-3450 5150);
PAINT RED (-3450 5150);
DISPLAY INVISIBLE (-3450 5150);
FORCEPROP 2 LAST CDS_LIB standard
J 0
(-2950 5100);
DISPLAY INVISIBLE (-2950 5100);
FORCEPROP 2 LAST BOM_COST IO_SLOT
J 0
(-3450 5200);
DISPLAY 0.829787 (-3450 5200);
DISPLAY INVISIBLE (-3450 5200);
FORCEPROP 1 LAST BODY_TYPE PLUMBING
J 2
(-2950 5050);
DISPLAY 0.702128 (-2950 5050);
PAINT GREEN (-2950 5050);
DISPLAY INVISIBLE (-2950 5050);
FORCEPROP 1 LAST HDL_TAP TRUE
J 2
(-3275 4975);
DISPLAY 0.702128 (-3275 4975);
PAINT GREEN (-3275 4975);
DISPLAY INVISIBLE (-3275 4975);
FORCEPROP 1 LAST PATH I443
J 2
(-2948 5100);
DISPLAY 0.872340 (-2948 5100);
PAINT GREEN (-2948 5100);
DISPLAY INVISIBLE (-2948 5100);
FORCEADD TAP..6
R 2
(-2950 5000);
FORCEPROP 3 LASTPIN (-3000 5000) SIG_NAME GMI_CPU1_G0_CPU0_G2_TX_DN<8>
J 0
(-2990 5010);
DISPLAY 0.659574 (-2990 5010);
PAINT MONO (-2990 5010);
DISPLAY INVISIBLE (-2990 5010);
FORCEPROP 1 LASTPIN (-3000 5000) BN 8
J 2
(-2948 5008);
DISPLAY 0.489362 (-2948 5008);
PAINT MONO (-2948 5008);
FORCEPROP 2 LAST ROOM RISER1
J 0
(-3450 5050);
DISPLAY 0.829787 (-3450 5050);
PAINT RED (-3450 5050);
DISPLAY INVISIBLE (-3450 5050);
FORCEPROP 2 LAST CDS_LIB standard
J 0
(-2950 5000);
DISPLAY INVISIBLE (-2950 5000);
FORCEPROP 2 LAST BOM_COST IO_SLOT
J 0
(-3450 5100);
DISPLAY 0.829787 (-3450 5100);
DISPLAY INVISIBLE (-3450 5100);
FORCEPROP 1 LAST BODY_TYPE PLUMBING
J 2
(-2950 4950);
DISPLAY 0.702128 (-2950 4950);
PAINT GREEN (-2950 4950);
DISPLAY INVISIBLE (-2950 4950);
FORCEPROP 1 LAST HDL_TAP TRUE
J 2
(-3275 4875);
DISPLAY 0.702128 (-3275 4875);
PAINT GREEN (-3275 4875);
DISPLAY INVISIBLE (-3275 4875);
FORCEPROP 1 LAST PATH I444
J 2
(-2948 5000);
DISPLAY 0.872340 (-2948 5000);
PAINT GREEN (-2948 5000);
DISPLAY INVISIBLE (-2948 5000);
FORCEADD TAP..6
R 2
(-2950 4900);
FORCEPROP 3 LASTPIN (-3000 4900) SIG_NAME GMI_CPU1_G0_CPU0_G2_TX_DN<7>
J 0
(-2990 4910);
DISPLAY 0.659574 (-2990 4910);
PAINT MONO (-2990 4910);
DISPLAY INVISIBLE (-2990 4910);
FORCEPROP 1 LASTPIN (-3000 4900) BN 7
J 2
(-2948 4908);
DISPLAY 0.489362 (-2948 4908);
PAINT MONO (-2948 4908);
FORCEPROP 2 LAST ROOM RISER1
J 0
(-3450 4950);
DISPLAY 0.829787 (-3450 4950);
PAINT RED (-3450 4950);
DISPLAY INVISIBLE (-3450 4950);
FORCEPROP 2 LAST CDS_LIB standard
J 0
(-2950 4900);
DISPLAY INVISIBLE (-2950 4900);
FORCEPROP 2 LAST BOM_COST IO_SLOT
J 0
(-3450 5000);
DISPLAY 0.829787 (-3450 5000);
DISPLAY INVISIBLE (-3450 5000);
FORCEPROP 1 LAST BODY_TYPE PLUMBING
J 2
(-2950 4850);
DISPLAY 0.702128 (-2950 4850);
PAINT GREEN (-2950 4850);
DISPLAY INVISIBLE (-2950 4850);
FORCEPROP 1 LAST HDL_TAP TRUE
J 2
(-3275 4775);
DISPLAY 0.702128 (-3275 4775);
PAINT GREEN (-3275 4775);
DISPLAY INVISIBLE (-3275 4775);
FORCEPROP 1 LAST PATH I445
J 2
(-2948 4900);
DISPLAY 0.872340 (-2948 4900);
PAINT GREEN (-2948 4900);
DISPLAY INVISIBLE (-2948 4900);
FORCEADD TAP..6
R 2
(-2950 4700);
FORCEPROP 3 LASTPIN (-3000 4700) SIG_NAME GMI_CPU1_G0_CPU0_G2_TX_DN<5>
J 0
(-2990 4710);
DISPLAY 0.659574 (-2990 4710);
PAINT MONO (-2990 4710);
DISPLAY INVISIBLE (-2990 4710);
FORCEPROP 1 LASTPIN (-3000 4700) BN 5
J 2
(-2948 4708);
DISPLAY 0.489362 (-2948 4708);
PAINT MONO (-2948 4708);
FORCEPROP 2 LAST ROOM RISER1
J 0
(-3450 4750);
DISPLAY 0.829787 (-3450 4750);
PAINT RED (-3450 4750);
DISPLAY INVISIBLE (-3450 4750);
FORCEPROP 2 LAST CDS_LIB standard
J 0
(-2950 4700);
DISPLAY INVISIBLE (-2950 4700);
FORCEPROP 2 LAST BOM_COST IO_SLOT
J 0
(-3450 4800);
DISPLAY 0.829787 (-3450 4800);
DISPLAY INVISIBLE (-3450 4800);
FORCEPROP 1 LAST BODY_TYPE PLUMBING
J 2
(-2950 4650);
DISPLAY 0.702128 (-2950 4650);
PAINT GREEN (-2950 4650);
DISPLAY INVISIBLE (-2950 4650);
FORCEPROP 1 LAST HDL_TAP TRUE
J 2
(-3275 4575);
DISPLAY 0.702128 (-3275 4575);
PAINT GREEN (-3275 4575);
DISPLAY INVISIBLE (-3275 4575);
FORCEPROP 1 LAST PATH I446
J 2
(-2948 4700);
DISPLAY 0.872340 (-2948 4700);
PAINT GREEN (-2948 4700);
DISPLAY INVISIBLE (-2948 4700);
FORCEADD TAP..6
R 2
(-2950 4800);
FORCEPROP 3 LASTPIN (-3000 4800) SIG_NAME GMI_CPU1_G0_CPU0_G2_TX_DN<6>
J 0
(-2990 4810);
DISPLAY 0.659574 (-2990 4810);
PAINT MONO (-2990 4810);
DISPLAY INVISIBLE (-2990 4810);
FORCEPROP 1 LASTPIN (-3000 4800) BN 6
J 2
(-2948 4808);
DISPLAY 0.489362 (-2948 4808);
PAINT MONO (-2948 4808);
FORCEPROP 2 LAST ROOM RISER1
J 0
(-3450 4850);
DISPLAY 0.829787 (-3450 4850);
PAINT RED (-3450 4850);
DISPLAY INVISIBLE (-3450 4850);
FORCEPROP 2 LAST CDS_LIB standard
J 0
(-2950 4800);
DISPLAY INVISIBLE (-2950 4800);
FORCEPROP 2 LAST BOM_COST IO_SLOT
J 0
(-3450 4900);
DISPLAY 0.829787 (-3450 4900);
DISPLAY INVISIBLE (-3450 4900);
FORCEPROP 1 LAST BODY_TYPE PLUMBING
J 2
(-2950 4750);
DISPLAY 0.702128 (-2950 4750);
PAINT GREEN (-2950 4750);
DISPLAY INVISIBLE (-2950 4750);
FORCEPROP 1 LAST HDL_TAP TRUE
J 2
(-3275 4675);
DISPLAY 0.702128 (-3275 4675);
PAINT GREEN (-3275 4675);
DISPLAY INVISIBLE (-3275 4675);
FORCEPROP 1 LAST PATH I447
J 2
(-2948 4800);
DISPLAY 0.872340 (-2948 4800);
PAINT GREEN (-2948 4800);
DISPLAY INVISIBLE (-2948 4800);
FORCEADD TAP..6
R 2
(-2950 4600);
FORCEPROP 3 LASTPIN (-3000 4600) SIG_NAME GMI_CPU1_G0_CPU0_G2_TX_DN<4>
J 0
(-2990 4610);
DISPLAY 0.659574 (-2990 4610);
PAINT MONO (-2990 4610);
DISPLAY INVISIBLE (-2990 4610);
FORCEPROP 1 LASTPIN (-3000 4600) BN 4
J 2
(-2948 4608);
DISPLAY 0.489362 (-2948 4608);
PAINT MONO (-2948 4608);
FORCEPROP 2 LAST ROOM RISER1
J 0
(-3450 4650);
DISPLAY 0.829787 (-3450 4650);
PAINT RED (-3450 4650);
DISPLAY INVISIBLE (-3450 4650);
FORCEPROP 2 LAST CDS_LIB standard
J 0
(-2950 4600);
DISPLAY INVISIBLE (-2950 4600);
FORCEPROP 2 LAST BOM_COST IO_SLOT
J 0
(-3450 4700);
DISPLAY 0.829787 (-3450 4700);
DISPLAY INVISIBLE (-3450 4700);
FORCEPROP 1 LAST BODY_TYPE PLUMBING
J 2
(-2950 4550);
DISPLAY 0.702128 (-2950 4550);
PAINT GREEN (-2950 4550);
DISPLAY INVISIBLE (-2950 4550);
FORCEPROP 1 LAST HDL_TAP TRUE
J 2
(-3275 4475);
DISPLAY 0.702128 (-3275 4475);
PAINT GREEN (-3275 4475);
DISPLAY INVISIBLE (-3275 4475);
FORCEPROP 1 LAST PATH I448
J 2
(-2948 4600);
DISPLAY 0.872340 (-2948 4600);
PAINT GREEN (-2948 4600);
DISPLAY INVISIBLE (-2948 4600);
FORCEADD TAP..6
R 2
(-2950 4500);
FORCEPROP 3 LASTPIN (-3000 4500) SIG_NAME GMI_CPU1_G0_CPU0_G2_TX_DN<3>
J 0
(-2990 4510);
DISPLAY 0.659574 (-2990 4510);
PAINT MONO (-2990 4510);
DISPLAY INVISIBLE (-2990 4510);
FORCEPROP 1 LASTPIN (-3000 4500) BN 3
J 2
(-2948 4508);
DISPLAY 0.489362 (-2948 4508);
PAINT MONO (-2948 4508);
FORCEPROP 2 LAST ROOM RISER1
J 0
(-3450 4550);
DISPLAY 0.829787 (-3450 4550);
PAINT RED (-3450 4550);
DISPLAY INVISIBLE (-3450 4550);
FORCEPROP 2 LAST CDS_LIB standard
J 0
(-2950 4500);
DISPLAY INVISIBLE (-2950 4500);
FORCEPROP 2 LAST BOM_COST IO_SLOT
J 0
(-3450 4600);
DISPLAY 0.829787 (-3450 4600);
DISPLAY INVISIBLE (-3450 4600);
FORCEPROP 1 LAST BODY_TYPE PLUMBING
J 2
(-2950 4450);
DISPLAY 0.702128 (-2950 4450);
PAINT GREEN (-2950 4450);
DISPLAY INVISIBLE (-2950 4450);
FORCEPROP 1 LAST HDL_TAP TRUE
J 2
(-3275 4375);
DISPLAY 0.702128 (-3275 4375);
PAINT GREEN (-3275 4375);
DISPLAY INVISIBLE (-3275 4375);
FORCEPROP 1 LAST PATH I449
J 2
(-2948 4500);
DISPLAY 0.872340 (-2948 4500);
PAINT GREEN (-2948 4500);
DISPLAY INVISIBLE (-2948 4500);
FORCEADD TAP..6
R 2
(-2950 4300);
FORCEPROP 3 LASTPIN (-3000 4300) SIG_NAME GMI_CPU1_G0_CPU0_G2_TX_DN<1>
J 0
(-2990 4310);
DISPLAY 0.659574 (-2990 4310);
PAINT MONO (-2990 4310);
DISPLAY INVISIBLE (-2990 4310);
FORCEPROP 1 LASTPIN (-3000 4300) BN 1
J 2
(-2948 4308);
DISPLAY 0.489362 (-2948 4308);
PAINT MONO (-2948 4308);
FORCEPROP 2 LAST ROOM RISER1
J 0
(-3450 4350);
DISPLAY 0.829787 (-3450 4350);
PAINT RED (-3450 4350);
DISPLAY INVISIBLE (-3450 4350);
FORCEPROP 2 LAST BOM_COST IO_SLOT
J 0
(-3450 4400);
DISPLAY 0.829787 (-3450 4400);
DISPLAY INVISIBLE (-3450 4400);
FORCEPROP 2 LAST CDS_LIB standard
J 0
(-2950 4300);
DISPLAY INVISIBLE (-2950 4300);
FORCEPROP 1 LAST BODY_TYPE PLUMBING
J 2
(-2950 4250);
DISPLAY 0.702128 (-2950 4250);
PAINT GREEN (-2950 4250);
DISPLAY INVISIBLE (-2950 4250);
FORCEPROP 1 LAST HDL_TAP TRUE
J 2
(-3275 4175);
DISPLAY 0.702128 (-3275 4175);
PAINT GREEN (-3275 4175);
DISPLAY INVISIBLE (-3275 4175);
FORCEPROP 1 LAST PATH I450
J 2
(-2948 4300);
DISPLAY 0.872340 (-2948 4300);
PAINT GREEN (-2948 4300);
DISPLAY INVISIBLE (-2948 4300);
FORCEADD TAP..6
R 2
(-2950 4400);
FORCEPROP 3 LASTPIN (-3000 4400) SIG_NAME GMI_CPU1_G0_CPU0_G2_TX_DN<2>
J 0
(-2990 4410);
DISPLAY 0.659574 (-2990 4410);
PAINT MONO (-2990 4410);
DISPLAY INVISIBLE (-2990 4410);
FORCEPROP 1 LASTPIN (-3000 4400) BN 2
J 2
(-2948 4408);
DISPLAY 0.489362 (-2948 4408);
PAINT MONO (-2948 4408);
FORCEPROP 2 LAST ROOM RISER1
J 0
(-3450 4450);
DISPLAY 0.829787 (-3450 4450);
PAINT RED (-3450 4450);
DISPLAY INVISIBLE (-3450 4450);
FORCEPROP 2 LAST CDS_LIB standard
J 0
(-2950 4400);
DISPLAY INVISIBLE (-2950 4400);
FORCEPROP 2 LAST BOM_COST IO_SLOT
J 0
(-3450 4500);
DISPLAY 0.829787 (-3450 4500);
DISPLAY INVISIBLE (-3450 4500);
FORCEPROP 1 LAST BODY_TYPE PLUMBING
J 2
(-2950 4350);
DISPLAY 0.702128 (-2950 4350);
PAINT GREEN (-2950 4350);
DISPLAY INVISIBLE (-2950 4350);
FORCEPROP 1 LAST HDL_TAP TRUE
J 2
(-3275 4275);
DISPLAY 0.702128 (-3275 4275);
PAINT GREEN (-3275 4275);
DISPLAY INVISIBLE (-3275 4275);
FORCEPROP 1 LAST PATH I451
J 2
(-2948 4400);
DISPLAY 0.872340 (-2948 4400);
PAINT GREEN (-2948 4400);
DISPLAY INVISIBLE (-2948 4400);
FORCEADD TAP..6
R 2
(-2950 4200);
FORCEPROP 3 LASTPIN (-3000 4200) SIG_NAME GMI_CPU1_G0_CPU0_G2_TX_DN<0>
J 0
(-2990 4210);
DISPLAY 0.659574 (-2990 4210);
PAINT MONO (-2990 4210);
DISPLAY INVISIBLE (-2990 4210);
FORCEPROP 1 LASTPIN (-3000 4200) BN 0
J 2
(-2948 4208);
DISPLAY 0.489362 (-2948 4208);
PAINT MONO (-2948 4208);
FORCEPROP 2 LAST ROOM RISER1
J 0
(-3450 4250);
DISPLAY 0.829787 (-3450 4250);
PAINT RED (-3450 4250);
DISPLAY INVISIBLE (-3450 4250);
FORCEPROP 2 LAST CDS_LIB standard
J 0
(-2950 4200);
DISPLAY INVISIBLE (-2950 4200);
FORCEPROP 2 LAST BOM_COST IO_SLOT
J 0
(-3450 4300);
DISPLAY 0.829787 (-3450 4300);
DISPLAY INVISIBLE (-3450 4300);
FORCEPROP 1 LAST BODY_TYPE PLUMBING
J 2
(-2950 4150);
DISPLAY 0.702128 (-2950 4150);
PAINT GREEN (-2950 4150);
DISPLAY INVISIBLE (-2950 4150);
FORCEPROP 1 LAST HDL_TAP TRUE
J 2
(-3275 4075);
DISPLAY 0.702128 (-3275 4075);
PAINT GREEN (-3275 4075);
DISPLAY INVISIBLE (-3275 4075);
FORCEPROP 1 LAST PATH I452
J 2
(-2948 4200);
DISPLAY 0.872340 (-2948 4200);
PAINT GREEN (-2948 4200);
DISPLAY INVISIBLE (-2948 4200);
FORCEADD TAP..6
(-6675 5700);
FORCEPROP 3 LASTPIN (-6625 5700) SIG_NAME GMI_CPU0_G2_CPU1_G0_TX_DN<15>
J 0
(-6615 5710);
DISPLAY 0.659574 (-6615 5710);
PAINT MONO (-6615 5710);
DISPLAY INVISIBLE (-6615 5710);
FORCEPROP 1 LASTPIN (-6625 5700) BN 15
J 0
(-6677 5708);
DISPLAY 0.489362 (-6677 5708);
PAINT MONO (-6677 5708);
FORCEPROP 2 LAST CDS_LIB mstr_standard
J 0
(-6675 5700);
DISPLAY INVISIBLE (-6675 5700);
FORCEPROP 1 LAST BODY_TYPE PLUMBING
J 0
(-6675 5650);
DISPLAY 0.574468 (-6675 5650);
PAINT GREEN (-6675 5650);
DISPLAY INVISIBLE (-6675 5650);
FORCEPROP 1 LAST HDL_TAP TRUE
J 0
(-6350 5575);
DISPLAY 0.574468 (-6350 5575);
PAINT GREEN (-6350 5575);
DISPLAY INVISIBLE (-6350 5575);
FORCEPROP 1 LAST PATH I453
J 0
(-6677 5700);
DISPLAY 0.872340 (-6677 5700);
PAINT GREEN (-6677 5700);
DISPLAY INVISIBLE (-6677 5700);
FORCEADD TAP..6
(-6675 5600);
FORCEPROP 3 LASTPIN (-6625 5600) SIG_NAME GMI_CPU0_G2_CPU1_G0_TX_DN<14>
J 0
(-6615 5610);
DISPLAY 0.659574 (-6615 5610);
PAINT MONO (-6615 5610);
DISPLAY INVISIBLE (-6615 5610);
FORCEPROP 1 LASTPIN (-6625 5600) BN 14
J 0
(-6677 5608);
DISPLAY 0.489362 (-6677 5608);
PAINT MONO (-6677 5608);
FORCEPROP 2 LAST CDS_LIB mstr_standard
J 0
(-6675 5600);
DISPLAY INVISIBLE (-6675 5600);
FORCEPROP 1 LAST BODY_TYPE PLUMBING
J 0
(-6675 5550);
DISPLAY 0.574468 (-6675 5550);
PAINT GREEN (-6675 5550);
DISPLAY INVISIBLE (-6675 5550);
FORCEPROP 1 LAST HDL_TAP TRUE
J 0
(-6350 5475);
DISPLAY 0.574468 (-6350 5475);
PAINT GREEN (-6350 5475);
DISPLAY INVISIBLE (-6350 5475);
FORCEPROP 1 LAST PATH I454
J 0
(-6677 5600);
DISPLAY 0.872340 (-6677 5600);
PAINT GREEN (-6677 5600);
DISPLAY INVISIBLE (-6677 5600);
FORCEADD TAP..6
(-6675 5500);
FORCEPROP 3 LASTPIN (-6625 5500) SIG_NAME GMI_CPU0_G2_CPU1_G0_TX_DN<13>
J 0
(-6615 5510);
DISPLAY 0.659574 (-6615 5510);
PAINT MONO (-6615 5510);
DISPLAY INVISIBLE (-6615 5510);
FORCEPROP 1 LASTPIN (-6625 5500) BN 13
J 0
(-6677 5508);
DISPLAY 0.489362 (-6677 5508);
PAINT MONO (-6677 5508);
FORCEPROP 2 LAST CDS_LIB standard
J 0
(-6675 5500);
DISPLAY INVISIBLE (-6675 5500);
FORCEPROP 1 LAST BODY_TYPE PLUMBING
J 0
(-6675 5450);
DISPLAY 0.574468 (-6675 5450);
PAINT GREEN (-6675 5450);
DISPLAY INVISIBLE (-6675 5450);
FORCEPROP 1 LAST HDL_TAP TRUE
J 0
(-6350 5375);
DISPLAY 0.574468 (-6350 5375);
PAINT GREEN (-6350 5375);
DISPLAY INVISIBLE (-6350 5375);
FORCEPROP 1 LAST PATH I455
J 0
(-6677 5500);
DISPLAY 0.872340 (-6677 5500);
PAINT GREEN (-6677 5500);
DISPLAY INVISIBLE (-6677 5500);
FORCEADD TAP..6
(-6675 5400);
FORCEPROP 3 LASTPIN (-6625 5400) SIG_NAME GMI_CPU0_G2_CPU1_G0_TX_DN<12>
J 0
(-6615 5410);
DISPLAY 0.659574 (-6615 5410);
PAINT MONO (-6615 5410);
DISPLAY INVISIBLE (-6615 5410);
FORCEPROP 1 LASTPIN (-6625 5400) BN 12
J 0
(-6677 5408);
DISPLAY 0.489362 (-6677 5408);
PAINT MONO (-6677 5408);
FORCEPROP 2 LAST CDS_LIB standard
J 0
(-6675 5400);
DISPLAY INVISIBLE (-6675 5400);
FORCEPROP 1 LAST BODY_TYPE PLUMBING
J 0
(-6675 5350);
DISPLAY 0.574468 (-6675 5350);
PAINT GREEN (-6675 5350);
DISPLAY INVISIBLE (-6675 5350);
FORCEPROP 1 LAST HDL_TAP TRUE
J 0
(-6350 5275);
DISPLAY 0.574468 (-6350 5275);
PAINT GREEN (-6350 5275);
DISPLAY INVISIBLE (-6350 5275);
FORCEPROP 1 LAST PATH I456
J 0
(-6677 5400);
DISPLAY 0.872340 (-6677 5400);
PAINT GREEN (-6677 5400);
DISPLAY INVISIBLE (-6677 5400);
FORCEADD TAP..6
(-6675 5200);
FORCEPROP 3 LASTPIN (-6625 5200) SIG_NAME GMI_CPU0_G2_CPU1_G0_TX_DN<10>
J 0
(-6615 5210);
DISPLAY 0.659574 (-6615 5210);
PAINT MONO (-6615 5210);
DISPLAY INVISIBLE (-6615 5210);
FORCEPROP 1 LASTPIN (-6625 5200) BN 10
J 0
(-6677 5208);
DISPLAY 0.489362 (-6677 5208);
PAINT MONO (-6677 5208);
FORCEPROP 2 LAST CDS_LIB standard
J 0
(-6675 5200);
DISPLAY INVISIBLE (-6675 5200);
FORCEPROP 1 LAST BODY_TYPE PLUMBING
J 0
(-6675 5150);
DISPLAY 0.574468 (-6675 5150);
PAINT GREEN (-6675 5150);
DISPLAY INVISIBLE (-6675 5150);
FORCEPROP 1 LAST HDL_TAP TRUE
J 0
(-6350 5075);
DISPLAY 0.574468 (-6350 5075);
PAINT GREEN (-6350 5075);
DISPLAY INVISIBLE (-6350 5075);
FORCEPROP 1 LAST PATH I457
J 0
(-6677 5200);
DISPLAY 0.872340 (-6677 5200);
PAINT GREEN (-6677 5200);
DISPLAY INVISIBLE (-6677 5200);
FORCEADD TAP..6
(-6675 5300);
FORCEPROP 3 LASTPIN (-6625 5300) SIG_NAME GMI_CPU0_G2_CPU1_G0_TX_DN<11>
J 0
(-6615 5310);
DISPLAY 0.659574 (-6615 5310);
PAINT MONO (-6615 5310);
DISPLAY INVISIBLE (-6615 5310);
FORCEPROP 1 LASTPIN (-6625 5300) BN 11
J 0
(-6677 5308);
DISPLAY 0.489362 (-6677 5308);
PAINT MONO (-6677 5308);
FORCEPROP 2 LAST CDS_LIB standard
J 0
(-6675 5300);
DISPLAY INVISIBLE (-6675 5300);
FORCEPROP 1 LAST BODY_TYPE PLUMBING
J 0
(-6675 5250);
DISPLAY 0.574468 (-6675 5250);
PAINT GREEN (-6675 5250);
DISPLAY INVISIBLE (-6675 5250);
FORCEPROP 1 LAST HDL_TAP TRUE
J 0
(-6350 5175);
DISPLAY 0.574468 (-6350 5175);
PAINT GREEN (-6350 5175);
DISPLAY INVISIBLE (-6350 5175);
FORCEPROP 1 LAST PATH I458
J 0
(-6677 5300);
DISPLAY 0.872340 (-6677 5300);
PAINT GREEN (-6677 5300);
DISPLAY INVISIBLE (-6677 5300);
FORCEADD TAP..6
(-6675 5100);
FORCEPROP 3 LASTPIN (-6625 5100) SIG_NAME GMI_CPU0_G2_CPU1_G0_TX_DN<9>
J 0
(-6615 5110);
DISPLAY 0.659574 (-6615 5110);
PAINT MONO (-6615 5110);
DISPLAY INVISIBLE (-6615 5110);
FORCEPROP 1 LASTPIN (-6625 5100) BN 9
J 0
(-6677 5108);
DISPLAY 0.489362 (-6677 5108);
PAINT MONO (-6677 5108);
FORCEPROP 2 LAST CDS_LIB standard
J 0
(-6675 5100);
DISPLAY INVISIBLE (-6675 5100);
FORCEPROP 1 LAST BODY_TYPE PLUMBING
J 0
(-6675 5050);
DISPLAY 0.574468 (-6675 5050);
PAINT GREEN (-6675 5050);
DISPLAY INVISIBLE (-6675 5050);
FORCEPROP 1 LAST HDL_TAP TRUE
J 0
(-6350 4975);
DISPLAY 0.574468 (-6350 4975);
PAINT GREEN (-6350 4975);
DISPLAY INVISIBLE (-6350 4975);
FORCEPROP 1 LAST PATH I459
J 0
(-6677 5100);
DISPLAY 0.872340 (-6677 5100);
PAINT GREEN (-6677 5100);
DISPLAY INVISIBLE (-6677 5100);
FORCEADD TAP..6
(-6675 5000);
FORCEPROP 3 LASTPIN (-6625 5000) SIG_NAME GMI_CPU0_G2_CPU1_G0_TX_DN<8>
J 0
(-6615 5010);
DISPLAY 0.659574 (-6615 5010);
PAINT MONO (-6615 5010);
DISPLAY INVISIBLE (-6615 5010);
FORCEPROP 1 LASTPIN (-6625 5000) BN 8
J 0
(-6677 5008);
DISPLAY 0.489362 (-6677 5008);
PAINT MONO (-6677 5008);
FORCEPROP 2 LAST CDS_LIB standard
J 0
(-6675 5000);
DISPLAY INVISIBLE (-6675 5000);
FORCEPROP 1 LAST BODY_TYPE PLUMBING
J 0
(-6675 4950);
DISPLAY 0.574468 (-6675 4950);
PAINT GREEN (-6675 4950);
DISPLAY INVISIBLE (-6675 4950);
FORCEPROP 1 LAST HDL_TAP TRUE
J 0
(-6350 4875);
DISPLAY 0.574468 (-6350 4875);
PAINT GREEN (-6350 4875);
DISPLAY INVISIBLE (-6350 4875);
FORCEPROP 1 LAST PATH I460
J 0
(-6677 5000);
DISPLAY 0.872340 (-6677 5000);
PAINT GREEN (-6677 5000);
DISPLAY INVISIBLE (-6677 5000);
FORCEADD TAP..6
(-6675 4900);
FORCEPROP 3 LASTPIN (-6625 4900) SIG_NAME GMI_CPU0_G2_CPU1_G0_TX_DN<7>
J 0
(-6615 4910);
DISPLAY 0.659574 (-6615 4910);
PAINT MONO (-6615 4910);
DISPLAY INVISIBLE (-6615 4910);
FORCEPROP 1 LASTPIN (-6625 4900) BN 7
J 0
(-6677 4908);
DISPLAY 0.489362 (-6677 4908);
PAINT MONO (-6677 4908);
FORCEPROP 2 LAST CDS_LIB standard
J 0
(-6675 4900);
DISPLAY INVISIBLE (-6675 4900);
FORCEPROP 1 LAST BODY_TYPE PLUMBING
J 0
(-6675 4850);
DISPLAY 0.574468 (-6675 4850);
PAINT GREEN (-6675 4850);
DISPLAY INVISIBLE (-6675 4850);
FORCEPROP 1 LAST HDL_TAP TRUE
J 0
(-6350 4775);
DISPLAY 0.574468 (-6350 4775);
PAINT GREEN (-6350 4775);
DISPLAY INVISIBLE (-6350 4775);
FORCEPROP 1 LAST PATH I461
J 0
(-6677 4900);
DISPLAY 0.872340 (-6677 4900);
PAINT GREEN (-6677 4900);
DISPLAY INVISIBLE (-6677 4900);
FORCEADD TAP..6
(-6675 4800);
FORCEPROP 3 LASTPIN (-6625 4800) SIG_NAME GMI_CPU0_G2_CPU1_G0_TX_DN<6>
J 0
(-6615 4810);
DISPLAY 0.659574 (-6615 4810);
PAINT MONO (-6615 4810);
DISPLAY INVISIBLE (-6615 4810);
FORCEPROP 1 LASTPIN (-6625 4800) BN 6
J 0
(-6677 4808);
DISPLAY 0.489362 (-6677 4808);
PAINT MONO (-6677 4808);
FORCEPROP 2 LAST CDS_LIB standard
J 0
(-6675 4800);
DISPLAY INVISIBLE (-6675 4800);
FORCEPROP 1 LAST BODY_TYPE PLUMBING
J 0
(-6675 4750);
DISPLAY 0.574468 (-6675 4750);
PAINT GREEN (-6675 4750);
DISPLAY INVISIBLE (-6675 4750);
FORCEPROP 1 LAST HDL_TAP TRUE
J 0
(-6350 4675);
DISPLAY 0.574468 (-6350 4675);
PAINT GREEN (-6350 4675);
DISPLAY INVISIBLE (-6350 4675);
FORCEPROP 1 LAST PATH I462
J 0
(-6677 4800);
DISPLAY 0.872340 (-6677 4800);
PAINT GREEN (-6677 4800);
DISPLAY INVISIBLE (-6677 4800);
FORCEADD TAP..6
(-6675 4700);
FORCEPROP 3 LASTPIN (-6625 4700) SIG_NAME GMI_CPU0_G2_CPU1_G0_TX_DN<5>
J 0
(-6615 4710);
DISPLAY 0.659574 (-6615 4710);
PAINT MONO (-6615 4710);
DISPLAY INVISIBLE (-6615 4710);
FORCEPROP 1 LASTPIN (-6625 4700) BN 5
J 0
(-6677 4708);
DISPLAY 0.489362 (-6677 4708);
PAINT MONO (-6677 4708);
FORCEPROP 2 LAST CDS_LIB standard
J 0
(-6675 4700);
DISPLAY INVISIBLE (-6675 4700);
FORCEPROP 1 LAST BODY_TYPE PLUMBING
J 0
(-6675 4650);
DISPLAY 0.574468 (-6675 4650);
PAINT GREEN (-6675 4650);
DISPLAY INVISIBLE (-6675 4650);
FORCEPROP 1 LAST HDL_TAP TRUE
J 0
(-6350 4575);
DISPLAY 0.574468 (-6350 4575);
PAINT GREEN (-6350 4575);
DISPLAY INVISIBLE (-6350 4575);
FORCEPROP 1 LAST PATH I463
J 0
(-6677 4700);
DISPLAY 0.872340 (-6677 4700);
PAINT GREEN (-6677 4700);
DISPLAY INVISIBLE (-6677 4700);
FORCEADD TAP..6
(-6675 4600);
FORCEPROP 3 LASTPIN (-6625 4600) SIG_NAME GMI_CPU0_G2_CPU1_G0_TX_DN<4>
J 0
(-6615 4610);
DISPLAY 0.659574 (-6615 4610);
PAINT MONO (-6615 4610);
DISPLAY INVISIBLE (-6615 4610);
FORCEPROP 1 LASTPIN (-6625 4600) BN 4
J 0
(-6677 4608);
DISPLAY 0.489362 (-6677 4608);
PAINT MONO (-6677 4608);
FORCEPROP 2 LAST CDS_LIB standard
J 0
(-6675 4600);
DISPLAY INVISIBLE (-6675 4600);
FORCEPROP 1 LAST BODY_TYPE PLUMBING
J 0
(-6675 4550);
DISPLAY 0.574468 (-6675 4550);
PAINT GREEN (-6675 4550);
DISPLAY INVISIBLE (-6675 4550);
FORCEPROP 1 LAST HDL_TAP TRUE
J 0
(-6350 4475);
DISPLAY 0.574468 (-6350 4475);
PAINT GREEN (-6350 4475);
DISPLAY INVISIBLE (-6350 4475);
FORCEPROP 1 LAST PATH I464
J 0
(-6677 4600);
DISPLAY 0.872340 (-6677 4600);
PAINT GREEN (-6677 4600);
DISPLAY INVISIBLE (-6677 4600);
FORCEADD TAP..6
(-6675 4500);
FORCEPROP 3 LASTPIN (-6625 4500) SIG_NAME GMI_CPU0_G2_CPU1_G0_TX_DN<3>
J 0
(-6615 4510);
DISPLAY 0.659574 (-6615 4510);
PAINT MONO (-6615 4510);
DISPLAY INVISIBLE (-6615 4510);
FORCEPROP 1 LASTPIN (-6625 4500) BN 3
J 0
(-6677 4508);
DISPLAY 0.489362 (-6677 4508);
PAINT MONO (-6677 4508);
FORCEPROP 2 LAST CDS_LIB standard
J 0
(-6675 4500);
DISPLAY INVISIBLE (-6675 4500);
FORCEPROP 1 LAST BODY_TYPE PLUMBING
J 0
(-6675 4450);
DISPLAY 0.574468 (-6675 4450);
PAINT GREEN (-6675 4450);
DISPLAY INVISIBLE (-6675 4450);
FORCEPROP 1 LAST HDL_TAP TRUE
J 0
(-6350 4375);
DISPLAY 0.574468 (-6350 4375);
PAINT GREEN (-6350 4375);
DISPLAY INVISIBLE (-6350 4375);
FORCEPROP 1 LAST PATH I465
J 0
(-6677 4500);
DISPLAY 0.872340 (-6677 4500);
PAINT GREEN (-6677 4500);
DISPLAY INVISIBLE (-6677 4500);
FORCEADD TAP..6
(-6675 4400);
FORCEPROP 3 LASTPIN (-6625 4400) SIG_NAME GMI_CPU0_G2_CPU1_G0_TX_DN<2>
J 0
(-6615 4410);
DISPLAY 0.659574 (-6615 4410);
PAINT MONO (-6615 4410);
DISPLAY INVISIBLE (-6615 4410);
FORCEPROP 1 LASTPIN (-6625 4400) BN 2
J 0
(-6677 4408);
DISPLAY 0.489362 (-6677 4408);
PAINT MONO (-6677 4408);
FORCEPROP 2 LAST CDS_LIB standard
J 0
(-6675 4400);
DISPLAY INVISIBLE (-6675 4400);
FORCEPROP 1 LAST BODY_TYPE PLUMBING
J 0
(-6675 4350);
DISPLAY 0.574468 (-6675 4350);
PAINT GREEN (-6675 4350);
DISPLAY INVISIBLE (-6675 4350);
FORCEPROP 1 LAST HDL_TAP TRUE
J 0
(-6350 4275);
DISPLAY 0.574468 (-6350 4275);
PAINT GREEN (-6350 4275);
DISPLAY INVISIBLE (-6350 4275);
FORCEPROP 1 LAST PATH I466
J 0
(-6677 4400);
DISPLAY 0.872340 (-6677 4400);
PAINT GREEN (-6677 4400);
DISPLAY INVISIBLE (-6677 4400);
FORCEADD TAP..6
(-6675 4200);
FORCEPROP 3 LASTPIN (-6625 4200) SIG_NAME GMI_CPU0_G2_CPU1_G0_TX_DN<0>
J 0
(-6615 4210);
DISPLAY 0.659574 (-6615 4210);
PAINT MONO (-6615 4210);
DISPLAY INVISIBLE (-6615 4210);
FORCEPROP 1 LASTPIN (-6625 4200) BN 0
J 0
(-6677 4208);
DISPLAY 0.489362 (-6677 4208);
PAINT MONO (-6677 4208);
FORCEPROP 2 LAST CDS_LIB standard
J 0
(-6675 4200);
DISPLAY INVISIBLE (-6675 4200);
FORCEPROP 1 LAST BODY_TYPE PLUMBING
J 0
(-6675 4150);
DISPLAY 0.574468 (-6675 4150);
PAINT GREEN (-6675 4150);
DISPLAY INVISIBLE (-6675 4150);
FORCEPROP 1 LAST HDL_TAP TRUE
J 0
(-6350 4075);
DISPLAY 0.574468 (-6350 4075);
PAINT GREEN (-6350 4075);
DISPLAY INVISIBLE (-6350 4075);
FORCEPROP 1 LAST PATH I467
J 0
(-6677 4200);
DISPLAY 0.872340 (-6677 4200);
PAINT GREEN (-6677 4200);
DISPLAY INVISIBLE (-6677 4200);
FORCEADD TAP..6
(-6675 4300);
FORCEPROP 3 LASTPIN (-6625 4300) SIG_NAME GMI_CPU0_G2_CPU1_G0_TX_DN<1>
J 0
(-6615 4310);
DISPLAY 0.659574 (-6615 4310);
PAINT MONO (-6615 4310);
DISPLAY INVISIBLE (-6615 4310);
FORCEPROP 1 LASTPIN (-6625 4300) BN 1
J 0
(-6677 4308);
DISPLAY 0.489362 (-6677 4308);
PAINT MONO (-6677 4308);
FORCEPROP 2 LAST CDS_LIB standard
J 0
(-6675 4300);
DISPLAY INVISIBLE (-6675 4300);
FORCEPROP 1 LAST BODY_TYPE PLUMBING
J 0
(-6675 4250);
DISPLAY 0.574468 (-6675 4250);
PAINT GREEN (-6675 4250);
DISPLAY INVISIBLE (-6675 4250);
FORCEPROP 1 LAST HDL_TAP TRUE
J 0
(-6350 4175);
DISPLAY 0.574468 (-6350 4175);
PAINT GREEN (-6350 4175);
DISPLAY INVISIBLE (-6350 4175);
FORCEPROP 1 LAST PATH I468
J 0
(-6677 4300);
DISPLAY 0.872340 (-6677 4300);
PAINT GREEN (-6677 4300);
DISPLAY INVISIBLE (-6677 4300);
FORCEADD OFFPAGE..1
(-7725 5925);
FORCEPROP 2 LASTPIN (-7675 5925) SIG_NAME GMI_CPU0_G2_CPU1_G0_TX_DN<0:15>
J 0
(-7685 5935);
DISPLAY 0.489362 (-7685 5935);
FORCEPROP 2 LAST $XR0 23 
J 0
(-7946 5925);
DISPLAY 0.638298 (-7946 5925);
PAINT MONO (-7946 5925);
FORCEPROP 2 LAST CDS_LIB standard
J 0
(-7725 5925);
DISPLAY INVISIBLE (-7725 5925);
FORCEPROP 1 LAST OFFPAGE TRUE
J 0
(-7400 5800);
DISPLAY 0.872340 (-7400 5800);
PAINT GREEN (-7400 5800);
DISPLAY INVISIBLE (-7400 5800);
FORCEPROP 1 LAST COMMENT_BODY TRUE
J 0
(-7600 5825);
DISPLAY 0.872340 (-7600 5825);
PAINT GREEN (-7600 5825);
DISPLAY INVISIBLE (-7600 5825);
FORCEPROP 2 LAST PATH I469
J 0
(-7925 5975);
DISPLAY 1.021277 (-7925 5975);
DISPLAY INVISIBLE (-7925 5975);
FORCEADD TAP..6
(-6650 2875);
FORCEPROP 3 LASTPIN (-6600 2875) SIG_NAME P5E_CPU1_G1_RX_DN<1>
J 0
(-6590 2885);
DISPLAY 0.659574 (-6590 2885);
PAINT MONO (-6590 2885);
DISPLAY INVISIBLE (-6590 2885);
FORCEPROP 1 LASTPIN (-6600 2875) BN 1
J 0
(-6652 2883);
DISPLAY 0.489362 (-6652 2883);
PAINT MONO (-6652 2883);
FORCEPROP 2 LAST CDS_LIB mstr_standard
J 0
(-6650 2875);
DISPLAY INVISIBLE (-6650 2875);
FORCEPROP 1 LAST BODY_TYPE PLUMBING
J 0
(-6650 2825);
DISPLAY 0.574468 (-6650 2825);
PAINT GREEN (-6650 2825);
DISPLAY INVISIBLE (-6650 2825);
FORCEPROP 1 LAST HDL_TAP TRUE
J 0
(-6325 2750);
DISPLAY 0.574468 (-6325 2750);
PAINT GREEN (-6325 2750);
DISPLAY INVISIBLE (-6325 2750);
FORCEPROP 1 LAST PATH I470
J 0
(-6652 2875);
DISPLAY 0.872340 (-6652 2875);
PAINT GREEN (-6652 2875);
DISPLAY INVISIBLE (-6652 2875);
FORCEADD TAP..6
(-6650 2975);
FORCEPROP 3 LASTPIN (-6600 2975) SIG_NAME P5E_CPU1_G1_RX_DN<0>
J 0
(-6590 2985);
DISPLAY 0.659574 (-6590 2985);
PAINT MONO (-6590 2985);
DISPLAY INVISIBLE (-6590 2985);
FORCEPROP 1 LASTPIN (-6600 2975) BN 0
J 0
(-6652 2983);
DISPLAY 0.489362 (-6652 2983);
PAINT MONO (-6652 2983);
FORCEPROP 2 LAST CDS_LIB mstr_standard
J 0
(-6650 2975);
DISPLAY INVISIBLE (-6650 2975);
FORCEPROP 1 LAST BODY_TYPE PLUMBING
J 0
(-6650 2925);
DISPLAY 0.574468 (-6650 2925);
PAINT GREEN (-6650 2925);
DISPLAY INVISIBLE (-6650 2925);
FORCEPROP 1 LAST HDL_TAP TRUE
J 0
(-6325 2850);
DISPLAY 0.574468 (-6325 2850);
PAINT GREEN (-6325 2850);
DISPLAY INVISIBLE (-6325 2850);
FORCEPROP 1 LAST PATH I471
J 0
(-6652 2975);
DISPLAY 0.872340 (-6652 2975);
PAINT GREEN (-6652 2975);
DISPLAY INVISIBLE (-6652 2975);
FORCEADD TAP..6
(-6650 2775);
FORCEPROP 3 LASTPIN (-6600 2775) SIG_NAME P5E_CPU1_G1_RX_DN<2>
J 0
(-6590 2785);
DISPLAY 0.659574 (-6590 2785);
PAINT MONO (-6590 2785);
DISPLAY INVISIBLE (-6590 2785);
FORCEPROP 1 LASTPIN (-6600 2775) BN 2
J 0
(-6652 2783);
DISPLAY 0.489362 (-6652 2783);
PAINT MONO (-6652 2783);
FORCEPROP 2 LAST CDS_LIB standard
J 0
(-6650 2775);
DISPLAY INVISIBLE (-6650 2775);
FORCEPROP 1 LAST BODY_TYPE PLUMBING
J 0
(-6650 2725);
DISPLAY 0.574468 (-6650 2725);
PAINT GREEN (-6650 2725);
DISPLAY INVISIBLE (-6650 2725);
FORCEPROP 1 LAST HDL_TAP TRUE
J 0
(-6325 2650);
DISPLAY 0.574468 (-6325 2650);
PAINT GREEN (-6325 2650);
DISPLAY INVISIBLE (-6325 2650);
FORCEPROP 1 LAST PATH I472
J 0
(-6652 2775);
DISPLAY 0.872340 (-6652 2775);
PAINT GREEN (-6652 2775);
DISPLAY INVISIBLE (-6652 2775);
FORCEADD TAP..6
(-6650 2675);
FORCEPROP 3 LASTPIN (-6600 2675) SIG_NAME P5E_CPU1_G1_RX_DN<3>
J 0
(-6590 2685);
DISPLAY 0.659574 (-6590 2685);
PAINT MONO (-6590 2685);
DISPLAY INVISIBLE (-6590 2685);
FORCEPROP 1 LASTPIN (-6600 2675) BN 3
J 0
(-6652 2683);
DISPLAY 0.489362 (-6652 2683);
PAINT MONO (-6652 2683);
FORCEPROP 2 LAST CDS_LIB standard
J 0
(-6650 2675);
DISPLAY INVISIBLE (-6650 2675);
FORCEPROP 1 LAST BODY_TYPE PLUMBING
J 0
(-6650 2625);
DISPLAY 0.574468 (-6650 2625);
PAINT GREEN (-6650 2625);
DISPLAY INVISIBLE (-6650 2625);
FORCEPROP 1 LAST HDL_TAP TRUE
J 0
(-6325 2550);
DISPLAY 0.574468 (-6325 2550);
PAINT GREEN (-6325 2550);
DISPLAY INVISIBLE (-6325 2550);
FORCEPROP 1 LAST PATH I473
J 0
(-6652 2675);
DISPLAY 0.872340 (-6652 2675);
PAINT GREEN (-6652 2675);
DISPLAY INVISIBLE (-6652 2675);
FORCEADD TAP..6
(-6650 2475);
FORCEPROP 3 LASTPIN (-6600 2475) SIG_NAME P5E_CPU1_G1_RX_DN<5>
J 0
(-6590 2485);
DISPLAY 0.659574 (-6590 2485);
PAINT MONO (-6590 2485);
DISPLAY INVISIBLE (-6590 2485);
FORCEPROP 1 LASTPIN (-6600 2475) BN 5
J 0
(-6652 2483);
DISPLAY 0.489362 (-6652 2483);
PAINT MONO (-6652 2483);
FORCEPROP 2 LAST CDS_LIB standard
J 0
(-6650 2475);
DISPLAY INVISIBLE (-6650 2475);
FORCEPROP 1 LAST BODY_TYPE PLUMBING
J 0
(-6650 2425);
DISPLAY 0.574468 (-6650 2425);
PAINT GREEN (-6650 2425);
DISPLAY INVISIBLE (-6650 2425);
FORCEPROP 1 LAST HDL_TAP TRUE
J 0
(-6325 2350);
DISPLAY 0.574468 (-6325 2350);
PAINT GREEN (-6325 2350);
DISPLAY INVISIBLE (-6325 2350);
FORCEPROP 1 LAST PATH I474
J 0
(-6652 2475);
DISPLAY 0.872340 (-6652 2475);
PAINT GREEN (-6652 2475);
DISPLAY INVISIBLE (-6652 2475);
FORCEADD TAP..6
(-6650 2575);
FORCEPROP 3 LASTPIN (-6600 2575) SIG_NAME P5E_CPU1_G1_RX_DN<4>
J 0
(-6590 2585);
DISPLAY 0.659574 (-6590 2585);
PAINT MONO (-6590 2585);
DISPLAY INVISIBLE (-6590 2585);
FORCEPROP 1 LASTPIN (-6600 2575) BN 4
J 0
(-6652 2583);
DISPLAY 0.489362 (-6652 2583);
PAINT MONO (-6652 2583);
FORCEPROP 2 LAST CDS_LIB standard
J 0
(-6650 2575);
DISPLAY INVISIBLE (-6650 2575);
FORCEPROP 1 LAST BODY_TYPE PLUMBING
J 0
(-6650 2525);
DISPLAY 0.574468 (-6650 2525);
PAINT GREEN (-6650 2525);
DISPLAY INVISIBLE (-6650 2525);
FORCEPROP 1 LAST HDL_TAP TRUE
J 0
(-6325 2450);
DISPLAY 0.574468 (-6325 2450);
PAINT GREEN (-6325 2450);
DISPLAY INVISIBLE (-6325 2450);
FORCEPROP 1 LAST PATH I475
J 0
(-6652 2575);
DISPLAY 0.872340 (-6652 2575);
PAINT GREEN (-6652 2575);
DISPLAY INVISIBLE (-6652 2575);
FORCEADD TAP..6
(-6650 2375);
FORCEPROP 3 LASTPIN (-6600 2375) SIG_NAME P5E_CPU1_G1_RX_DN<6>
J 0
(-6590 2385);
DISPLAY 0.659574 (-6590 2385);
PAINT MONO (-6590 2385);
DISPLAY INVISIBLE (-6590 2385);
FORCEPROP 1 LASTPIN (-6600 2375) BN 6
J 0
(-6652 2383);
DISPLAY 0.489362 (-6652 2383);
PAINT MONO (-6652 2383);
FORCEPROP 2 LAST CDS_LIB standard
J 0
(-6650 2375);
DISPLAY INVISIBLE (-6650 2375);
FORCEPROP 1 LAST BODY_TYPE PLUMBING
J 0
(-6650 2325);
DISPLAY 0.574468 (-6650 2325);
PAINT GREEN (-6650 2325);
DISPLAY INVISIBLE (-6650 2325);
FORCEPROP 1 LAST HDL_TAP TRUE
J 0
(-6325 2250);
DISPLAY 0.574468 (-6325 2250);
PAINT GREEN (-6325 2250);
DISPLAY INVISIBLE (-6325 2250);
FORCEPROP 1 LAST PATH I476
J 0
(-6652 2375);
DISPLAY 0.872340 (-6652 2375);
PAINT GREEN (-6652 2375);
DISPLAY INVISIBLE (-6652 2375);
FORCEADD TAP..6
(-6650 2275);
FORCEPROP 3 LASTPIN (-6600 2275) SIG_NAME P5E_CPU1_G1_RX_DN<7>
J 0
(-6590 2285);
DISPLAY 0.659574 (-6590 2285);
PAINT MONO (-6590 2285);
DISPLAY INVISIBLE (-6590 2285);
FORCEPROP 1 LASTPIN (-6600 2275) BN 7
J 0
(-6652 2283);
DISPLAY 0.489362 (-6652 2283);
PAINT MONO (-6652 2283);
FORCEPROP 2 LAST CDS_LIB standard
J 0
(-6650 2275);
DISPLAY INVISIBLE (-6650 2275);
FORCEPROP 1 LAST BODY_TYPE PLUMBING
J 0
(-6650 2225);
DISPLAY 0.574468 (-6650 2225);
PAINT GREEN (-6650 2225);
DISPLAY INVISIBLE (-6650 2225);
FORCEPROP 1 LAST HDL_TAP TRUE
J 0
(-6325 2150);
DISPLAY 0.574468 (-6325 2150);
PAINT GREEN (-6325 2150);
DISPLAY INVISIBLE (-6325 2150);
FORCEPROP 1 LAST PATH I477
J 0
(-6652 2275);
DISPLAY 0.872340 (-6652 2275);
PAINT GREEN (-6652 2275);
DISPLAY INVISIBLE (-6652 2275);
FORCEADD TAP..6
(-6650 2175);
FORCEPROP 3 LASTPIN (-6600 2175) SIG_NAME P5E_CPU1_G1_RX_DN<8>
J 0
(-6590 2185);
DISPLAY 0.659574 (-6590 2185);
PAINT MONO (-6590 2185);
DISPLAY INVISIBLE (-6590 2185);
FORCEPROP 1 LASTPIN (-6600 2175) BN 8
J 0
(-6652 2183);
DISPLAY 0.489362 (-6652 2183);
PAINT MONO (-6652 2183);
FORCEPROP 2 LAST CDS_LIB standard
J 0
(-6650 2175);
DISPLAY INVISIBLE (-6650 2175);
FORCEPROP 1 LAST BODY_TYPE PLUMBING
J 0
(-6650 2125);
DISPLAY 0.574468 (-6650 2125);
PAINT GREEN (-6650 2125);
DISPLAY INVISIBLE (-6650 2125);
FORCEPROP 1 LAST HDL_TAP TRUE
J 0
(-6325 2050);
DISPLAY 0.574468 (-6325 2050);
PAINT GREEN (-6325 2050);
DISPLAY INVISIBLE (-6325 2050);
FORCEPROP 1 LAST PATH I478
J 0
(-6652 2175);
DISPLAY 0.872340 (-6652 2175);
PAINT GREEN (-6652 2175);
DISPLAY INVISIBLE (-6652 2175);
FORCEADD TAP..6
(-6650 1975);
FORCEPROP 3 LASTPIN (-6600 1975) SIG_NAME P5E_CPU1_G1_RX_DN<10>
J 0
(-6590 1985);
DISPLAY 0.659574 (-6590 1985);
PAINT MONO (-6590 1985);
DISPLAY INVISIBLE (-6590 1985);
FORCEPROP 1 LASTPIN (-6600 1975) BN 10
J 0
(-6652 1983);
DISPLAY 0.489362 (-6652 1983);
PAINT MONO (-6652 1983);
FORCEPROP 2 LAST CDS_LIB standard
J 0
(-6650 1975);
DISPLAY INVISIBLE (-6650 1975);
FORCEPROP 1 LAST BODY_TYPE PLUMBING
J 0
(-6650 1925);
DISPLAY 0.574468 (-6650 1925);
PAINT GREEN (-6650 1925);
DISPLAY INVISIBLE (-6650 1925);
FORCEPROP 1 LAST HDL_TAP TRUE
J 0
(-6325 1850);
DISPLAY 0.574468 (-6325 1850);
PAINT GREEN (-6325 1850);
DISPLAY INVISIBLE (-6325 1850);
FORCEPROP 1 LAST PATH I479
J 0
(-6652 1975);
DISPLAY 0.872340 (-6652 1975);
PAINT GREEN (-6652 1975);
DISPLAY INVISIBLE (-6652 1975);
FORCEADD TAP..6
(-6650 2075);
FORCEPROP 3 LASTPIN (-6600 2075) SIG_NAME P5E_CPU1_G1_RX_DN<9>
J 0
(-6590 2085);
DISPLAY 0.659574 (-6590 2085);
PAINT MONO (-6590 2085);
DISPLAY INVISIBLE (-6590 2085);
FORCEPROP 1 LASTPIN (-6600 2075) BN 9
J 0
(-6652 2083);
DISPLAY 0.489362 (-6652 2083);
PAINT MONO (-6652 2083);
FORCEPROP 2 LAST CDS_LIB standard
J 0
(-6650 2075);
DISPLAY INVISIBLE (-6650 2075);
FORCEPROP 1 LAST BODY_TYPE PLUMBING
J 0
(-6650 2025);
DISPLAY 0.574468 (-6650 2025);
PAINT GREEN (-6650 2025);
DISPLAY INVISIBLE (-6650 2025);
FORCEPROP 1 LAST HDL_TAP TRUE
J 0
(-6325 1950);
DISPLAY 0.574468 (-6325 1950);
PAINT GREEN (-6325 1950);
DISPLAY INVISIBLE (-6325 1950);
FORCEPROP 1 LAST PATH I480
J 0
(-6652 2075);
DISPLAY 0.872340 (-6652 2075);
PAINT GREEN (-6652 2075);
DISPLAY INVISIBLE (-6652 2075);
FORCEADD TAP..6
(-6650 1875);
FORCEPROP 3 LASTPIN (-6600 1875) SIG_NAME P5E_CPU1_G1_RX_DN<11>
J 0
(-6590 1885);
DISPLAY 0.659574 (-6590 1885);
PAINT MONO (-6590 1885);
DISPLAY INVISIBLE (-6590 1885);
FORCEPROP 1 LASTPIN (-6600 1875) BN 11
J 0
(-6652 1883);
DISPLAY 0.489362 (-6652 1883);
PAINT MONO (-6652 1883);
FORCEPROP 2 LAST CDS_LIB standard
J 0
(-6650 1875);
DISPLAY INVISIBLE (-6650 1875);
FORCEPROP 1 LAST BODY_TYPE PLUMBING
J 0
(-6650 1825);
DISPLAY 0.574468 (-6650 1825);
PAINT GREEN (-6650 1825);
DISPLAY INVISIBLE (-6650 1825);
FORCEPROP 1 LAST HDL_TAP TRUE
J 0
(-6325 1750);
DISPLAY 0.574468 (-6325 1750);
PAINT GREEN (-6325 1750);
DISPLAY INVISIBLE (-6325 1750);
FORCEPROP 1 LAST PATH I481
J 0
(-6652 1875);
DISPLAY 0.872340 (-6652 1875);
PAINT GREEN (-6652 1875);
DISPLAY INVISIBLE (-6652 1875);
FORCEADD TAP..6
(-6650 1775);
FORCEPROP 3 LASTPIN (-6600 1775) SIG_NAME P5E_CPU1_G1_RX_DN<12>
J 0
(-6590 1785);
DISPLAY 0.659574 (-6590 1785);
PAINT MONO (-6590 1785);
DISPLAY INVISIBLE (-6590 1785);
FORCEPROP 1 LASTPIN (-6600 1775) BN 12
J 0
(-6652 1783);
DISPLAY 0.489362 (-6652 1783);
PAINT MONO (-6652 1783);
FORCEPROP 2 LAST CDS_LIB standard
J 0
(-6650 1775);
DISPLAY INVISIBLE (-6650 1775);
FORCEPROP 1 LAST BODY_TYPE PLUMBING
J 0
(-6650 1725);
DISPLAY 0.574468 (-6650 1725);
PAINT GREEN (-6650 1725);
DISPLAY INVISIBLE (-6650 1725);
FORCEPROP 1 LAST HDL_TAP TRUE
J 0
(-6325 1650);
DISPLAY 0.574468 (-6325 1650);
PAINT GREEN (-6325 1650);
DISPLAY INVISIBLE (-6325 1650);
FORCEPROP 1 LAST PATH I482
J 0
(-6652 1775);
DISPLAY 0.872340 (-6652 1775);
PAINT GREEN (-6652 1775);
DISPLAY INVISIBLE (-6652 1775);
FORCEADD TAP..6
(-6650 1675);
FORCEPROP 3 LASTPIN (-6600 1675) SIG_NAME P5E_CPU1_G1_RX_DN<13>
J 0
(-6590 1685);
DISPLAY 0.659574 (-6590 1685);
PAINT MONO (-6590 1685);
DISPLAY INVISIBLE (-6590 1685);
FORCEPROP 1 LASTPIN (-6600 1675) BN 13
J 0
(-6652 1683);
DISPLAY 0.489362 (-6652 1683);
PAINT MONO (-6652 1683);
FORCEPROP 2 LAST CDS_LIB standard
J 0
(-6650 1675);
DISPLAY INVISIBLE (-6650 1675);
FORCEPROP 1 LAST BODY_TYPE PLUMBING
J 0
(-6650 1625);
DISPLAY 0.574468 (-6650 1625);
PAINT GREEN (-6650 1625);
DISPLAY INVISIBLE (-6650 1625);
FORCEPROP 1 LAST HDL_TAP TRUE
J 0
(-6325 1550);
DISPLAY 0.574468 (-6325 1550);
PAINT GREEN (-6325 1550);
DISPLAY INVISIBLE (-6325 1550);
FORCEPROP 1 LAST PATH I483
J 0
(-6652 1675);
DISPLAY 0.872340 (-6652 1675);
PAINT GREEN (-6652 1675);
DISPLAY INVISIBLE (-6652 1675);
FORCEADD TAP..6
(-6650 1575);
FORCEPROP 3 LASTPIN (-6600 1575) SIG_NAME P5E_CPU1_G1_RX_DN<14>
J 0
(-6590 1585);
DISPLAY 0.659574 (-6590 1585);
PAINT MONO (-6590 1585);
DISPLAY INVISIBLE (-6590 1585);
FORCEPROP 1 LASTPIN (-6600 1575) BN 14
J 0
(-6652 1583);
DISPLAY 0.489362 (-6652 1583);
PAINT MONO (-6652 1583);
FORCEPROP 2 LAST CDS_LIB standard
J 0
(-6650 1575);
DISPLAY INVISIBLE (-6650 1575);
FORCEPROP 1 LAST BODY_TYPE PLUMBING
J 0
(-6650 1525);
DISPLAY 0.574468 (-6650 1525);
PAINT GREEN (-6650 1525);
DISPLAY INVISIBLE (-6650 1525);
FORCEPROP 1 LAST HDL_TAP TRUE
J 0
(-6325 1450);
DISPLAY 0.574468 (-6325 1450);
PAINT GREEN (-6325 1450);
DISPLAY INVISIBLE (-6325 1450);
FORCEPROP 1 LAST PATH I484
J 0
(-6652 1575);
DISPLAY 0.872340 (-6652 1575);
PAINT GREEN (-6652 1575);
DISPLAY INVISIBLE (-6652 1575);
FORCEADD TAP..6
(-6650 1475);
FORCEPROP 3 LASTPIN (-6600 1475) SIG_NAME P5E_CPU1_G1_RX_DN<15>
J 0
(-6590 1485);
DISPLAY 0.659574 (-6590 1485);
PAINT MONO (-6590 1485);
DISPLAY INVISIBLE (-6590 1485);
FORCEPROP 1 LASTPIN (-6600 1475) BN 15
J 0
(-6652 1483);
DISPLAY 0.489362 (-6652 1483);
PAINT MONO (-6652 1483);
FORCEPROP 2 LAST CDS_LIB standard
J 0
(-6650 1475);
DISPLAY INVISIBLE (-6650 1475);
FORCEPROP 1 LAST BODY_TYPE PLUMBING
J 0
(-6650 1425);
DISPLAY 0.574468 (-6650 1425);
PAINT GREEN (-6650 1425);
DISPLAY INVISIBLE (-6650 1425);
FORCEPROP 1 LAST HDL_TAP TRUE
J 0
(-6325 1350);
DISPLAY 0.574468 (-6325 1350);
PAINT GREEN (-6325 1350);
DISPLAY INVISIBLE (-6325 1350);
FORCEPROP 1 LAST PATH I485
J 0
(-6652 1475);
DISPLAY 0.872340 (-6652 1475);
PAINT GREEN (-6652 1475);
DISPLAY INVISIBLE (-6652 1475);
FORCEADD OFFPAGE..1
(-7600 3200);
FORCEPROP 2 LAST $XR0 137 
J 0
(-7852 3200);
DISPLAY 0.638298 (-7852 3200);
PAINT MONO (-7852 3200);
FORCEPROP 2 LAST CDS_LIB standard
J 0
(-7600 3200);
DISPLAY INVISIBLE (-7600 3200);
FORCEPROP 1 LAST OFFPAGE TRUE
J 0
(-7275 3075);
DISPLAY 0.872340 (-7275 3075);
PAINT GREEN (-7275 3075);
DISPLAY INVISIBLE (-7275 3075);
FORCEPROP 1 LAST COMMENT_BODY TRUE
J 0
(-7475 3100);
DISPLAY 0.872340 (-7475 3100);
PAINT GREEN (-7475 3100);
DISPLAY INVISIBLE (-7475 3100);
FORCEPROP 2 LAST PATH I486
J 0
(-7800 3250);
DISPLAY 1.021277 (-7800 3250);
DISPLAY INVISIBLE (-7800 3250);
FORCEADD OFFPAGE..2
(-1800 3200);
FORCEPROP 2 LAST $XR0 67 
J 0
(-1611 3200);
DISPLAY 0.638298 (-1611 3200);
PAINT MONO (-1611 3200);
FORCEPROP 2 LAST CDS_LIB standard
J 0
(-1800 3200);
DISPLAY INVISIBLE (-1800 3200);
FORCEPROP 1 LAST OFFPAGE TRUE
J 0
(-1475 3075);
DISPLAY 0.872340 (-1475 3075);
PAINT GREEN (-1475 3075);
DISPLAY INVISIBLE (-1475 3075);
FORCEPROP 1 LAST COMMENT_BODY TRUE
J 0
(-1845 3105);
DISPLAY 0.872340 (-1845 3105);
PAINT GREEN (-1845 3105);
DISPLAY INVISIBLE (-1845 3105);
FORCEPROP 2 LAST PATH I487
J 0
(-1600 3250);
DISPLAY 1.021277 (-1600 3250);
DISPLAY INVISIBLE (-1600 3250);
FORCEADD TAP..6
R 2
(-2925 2975);
FORCEPROP 3 LASTPIN (-2975 2975) SIG_NAME P5E_CPU1_G1_TX_DN<0>
J 0
(-2965 2985);
DISPLAY 0.659574 (-2965 2985);
PAINT MONO (-2965 2985);
DISPLAY INVISIBLE (-2965 2985);
FORCEPROP 1 LASTPIN (-2975 2975) BN 0
J 2
(-2923 2983);
DISPLAY 0.489362 (-2923 2983);
PAINT MONO (-2923 2983);
FORCEPROP 2 LAST ROOM RISER1
J 0
(-3425 3025);
DISPLAY 0.829787 (-3425 3025);
PAINT RED (-3425 3025);
DISPLAY INVISIBLE (-3425 3025);
FORCEPROP 2 LAST CDS_LIB mstr_standard
J 0
(-2925 2975);
DISPLAY INVISIBLE (-2925 2975);
FORCEPROP 2 LAST BOM_COST IO_SLOT
J 0
(-3425 3075);
DISPLAY 0.829787 (-3425 3075);
DISPLAY INVISIBLE (-3425 3075);
FORCEPROP 1 LAST BODY_TYPE PLUMBING
J 2
(-2925 2925);
DISPLAY 0.702128 (-2925 2925);
PAINT GREEN (-2925 2925);
DISPLAY INVISIBLE (-2925 2925);
FORCEPROP 1 LAST HDL_TAP TRUE
J 2
(-3250 2850);
DISPLAY 0.702128 (-3250 2850);
PAINT GREEN (-3250 2850);
DISPLAY INVISIBLE (-3250 2850);
FORCEPROP 1 LAST PATH I488
J 2
(-2923 2975);
DISPLAY 0.872340 (-2923 2975);
PAINT GREEN (-2923 2975);
DISPLAY INVISIBLE (-2923 2975);
FORCEADD TAP..6
R 2
(-2925 2875);
FORCEPROP 3 LASTPIN (-2975 2875) SIG_NAME P5E_CPU1_G1_TX_DN<1>
J 0
(-2965 2885);
DISPLAY 0.659574 (-2965 2885);
PAINT MONO (-2965 2885);
DISPLAY INVISIBLE (-2965 2885);
FORCEPROP 1 LASTPIN (-2975 2875) BN 1
J 2
(-2923 2883);
DISPLAY 0.489362 (-2923 2883);
PAINT MONO (-2923 2883);
FORCEPROP 2 LAST ROOM RISER1
J 0
(-3425 2925);
DISPLAY 0.829787 (-3425 2925);
PAINT RED (-3425 2925);
DISPLAY INVISIBLE (-3425 2925);
FORCEPROP 2 LAST BOM_COST IO_SLOT
J 0
(-3425 2975);
DISPLAY 0.829787 (-3425 2975);
DISPLAY INVISIBLE (-3425 2975);
FORCEPROP 2 LAST CDS_LIB mstr_standard
J 0
(-2925 2875);
DISPLAY INVISIBLE (-2925 2875);
FORCEPROP 1 LAST BODY_TYPE PLUMBING
J 2
(-2925 2825);
DISPLAY 0.702128 (-2925 2825);
PAINT GREEN (-2925 2825);
DISPLAY INVISIBLE (-2925 2825);
FORCEPROP 1 LAST HDL_TAP TRUE
J 2
(-3250 2750);
DISPLAY 0.702128 (-3250 2750);
PAINT GREEN (-3250 2750);
DISPLAY INVISIBLE (-3250 2750);
FORCEPROP 1 LAST PATH I489
J 2
(-2923 2875);
DISPLAY 0.872340 (-2923 2875);
PAINT GREEN (-2923 2875);
DISPLAY INVISIBLE (-2923 2875);
FORCEADD TAP..6
R 2
(-2925 2775);
FORCEPROP 3 LASTPIN (-2975 2775) SIG_NAME P5E_CPU1_G1_TX_DN<2>
J 0
(-2965 2785);
DISPLAY 0.659574 (-2965 2785);
PAINT MONO (-2965 2785);
DISPLAY INVISIBLE (-2965 2785);
FORCEPROP 1 LASTPIN (-2975 2775) BN 2
J 2
(-2923 2783);
DISPLAY 0.489362 (-2923 2783);
PAINT MONO (-2923 2783);
FORCEPROP 2 LAST ROOM RISER1
J 0
(-3425 2825);
DISPLAY 0.829787 (-3425 2825);
PAINT RED (-3425 2825);
DISPLAY INVISIBLE (-3425 2825);
FORCEPROP 2 LAST BOM_COST IO_SLOT
J 0
(-3425 2875);
DISPLAY 0.829787 (-3425 2875);
DISPLAY INVISIBLE (-3425 2875);
FORCEPROP 2 LAST CDS_LIB standard
J 0
(-2925 2775);
DISPLAY INVISIBLE (-2925 2775);
FORCEPROP 1 LAST BODY_TYPE PLUMBING
J 2
(-2925 2725);
DISPLAY 0.702128 (-2925 2725);
PAINT GREEN (-2925 2725);
DISPLAY INVISIBLE (-2925 2725);
FORCEPROP 1 LAST HDL_TAP TRUE
J 2
(-3250 2650);
DISPLAY 0.702128 (-3250 2650);
PAINT GREEN (-3250 2650);
DISPLAY INVISIBLE (-3250 2650);
FORCEPROP 1 LAST PATH I490
J 2
(-2923 2775);
DISPLAY 0.872340 (-2923 2775);
PAINT GREEN (-2923 2775);
DISPLAY INVISIBLE (-2923 2775);
FORCEADD TAP..6
R 2
(-2925 2675);
FORCEPROP 3 LASTPIN (-2975 2675) SIG_NAME P5E_CPU1_G1_TX_DN<3>
J 0
(-2965 2685);
DISPLAY 0.659574 (-2965 2685);
PAINT MONO (-2965 2685);
DISPLAY INVISIBLE (-2965 2685);
FORCEPROP 1 LASTPIN (-2975 2675) BN 3
J 2
(-2923 2683);
DISPLAY 0.489362 (-2923 2683);
PAINT MONO (-2923 2683);
FORCEPROP 2 LAST ROOM RISER1
J 0
(-3425 2725);
DISPLAY 0.829787 (-3425 2725);
PAINT RED (-3425 2725);
DISPLAY INVISIBLE (-3425 2725);
FORCEPROP 2 LAST BOM_COST IO_SLOT
J 0
(-3425 2775);
DISPLAY 0.829787 (-3425 2775);
DISPLAY INVISIBLE (-3425 2775);
FORCEPROP 2 LAST CDS_LIB standard
J 0
(-2925 2675);
DISPLAY INVISIBLE (-2925 2675);
FORCEPROP 1 LAST BODY_TYPE PLUMBING
J 2
(-2925 2625);
DISPLAY 0.702128 (-2925 2625);
PAINT GREEN (-2925 2625);
DISPLAY INVISIBLE (-2925 2625);
FORCEPROP 1 LAST HDL_TAP TRUE
J 2
(-3250 2550);
DISPLAY 0.702128 (-3250 2550);
PAINT GREEN (-3250 2550);
DISPLAY INVISIBLE (-3250 2550);
FORCEPROP 1 LAST PATH I491
J 2
(-2923 2675);
DISPLAY 0.872340 (-2923 2675);
PAINT GREEN (-2923 2675);
DISPLAY INVISIBLE (-2923 2675);
FORCEADD TAP..6
R 2
(-2925 2575);
FORCEPROP 3 LASTPIN (-2975 2575) SIG_NAME P5E_CPU1_G1_TX_DN<4>
J 0
(-2965 2585);
DISPLAY 0.659574 (-2965 2585);
PAINT MONO (-2965 2585);
DISPLAY INVISIBLE (-2965 2585);
FORCEPROP 1 LASTPIN (-2975 2575) BN 4
J 2
(-2923 2583);
DISPLAY 0.489362 (-2923 2583);
PAINT MONO (-2923 2583);
FORCEPROP 2 LAST ROOM RISER1
J 0
(-3425 2625);
DISPLAY 0.829787 (-3425 2625);
PAINT RED (-3425 2625);
DISPLAY INVISIBLE (-3425 2625);
FORCEPROP 2 LAST BOM_COST IO_SLOT
J 0
(-3425 2675);
DISPLAY 0.829787 (-3425 2675);
DISPLAY INVISIBLE (-3425 2675);
FORCEPROP 2 LAST CDS_LIB standard
J 0
(-2925 2575);
DISPLAY INVISIBLE (-2925 2575);
FORCEPROP 1 LAST BODY_TYPE PLUMBING
J 2
(-2925 2525);
DISPLAY 0.702128 (-2925 2525);
PAINT GREEN (-2925 2525);
DISPLAY INVISIBLE (-2925 2525);
FORCEPROP 1 LAST HDL_TAP TRUE
J 2
(-3250 2450);
DISPLAY 0.702128 (-3250 2450);
PAINT GREEN (-3250 2450);
DISPLAY INVISIBLE (-3250 2450);
FORCEPROP 1 LAST PATH I492
J 2
(-2923 2575);
DISPLAY 0.872340 (-2923 2575);
PAINT GREEN (-2923 2575);
DISPLAY INVISIBLE (-2923 2575);
FORCEADD TAP..6
R 2
(-2925 2475);
FORCEPROP 3 LASTPIN (-2975 2475) SIG_NAME P5E_CPU1_G1_TX_DN<5>
J 0
(-2965 2485);
DISPLAY 0.659574 (-2965 2485);
PAINT MONO (-2965 2485);
DISPLAY INVISIBLE (-2965 2485);
FORCEPROP 1 LASTPIN (-2975 2475) BN 5
J 2
(-2923 2483);
DISPLAY 0.489362 (-2923 2483);
PAINT MONO (-2923 2483);
FORCEPROP 2 LAST ROOM RISER1
J 0
(-3425 2525);
DISPLAY 0.829787 (-3425 2525);
PAINT RED (-3425 2525);
DISPLAY INVISIBLE (-3425 2525);
FORCEPROP 2 LAST BOM_COST IO_SLOT
J 0
(-3425 2575);
DISPLAY 0.829787 (-3425 2575);
DISPLAY INVISIBLE (-3425 2575);
FORCEPROP 2 LAST CDS_LIB standard
J 0
(-2925 2475);
DISPLAY INVISIBLE (-2925 2475);
FORCEPROP 1 LAST BODY_TYPE PLUMBING
J 2
(-2925 2425);
DISPLAY 0.702128 (-2925 2425);
PAINT GREEN (-2925 2425);
DISPLAY INVISIBLE (-2925 2425);
FORCEPROP 1 LAST HDL_TAP TRUE
J 2
(-3250 2350);
DISPLAY 0.702128 (-3250 2350);
PAINT GREEN (-3250 2350);
DISPLAY INVISIBLE (-3250 2350);
FORCEPROP 1 LAST PATH I493
J 2
(-2923 2475);
DISPLAY 0.872340 (-2923 2475);
PAINT GREEN (-2923 2475);
DISPLAY INVISIBLE (-2923 2475);
FORCEADD TAP..6
R 2
(-2925 2375);
FORCEPROP 3 LASTPIN (-2975 2375) SIG_NAME P5E_CPU1_G1_TX_DN<6>
J 0
(-2965 2385);
DISPLAY 0.659574 (-2965 2385);
PAINT MONO (-2965 2385);
DISPLAY INVISIBLE (-2965 2385);
FORCEPROP 1 LASTPIN (-2975 2375) BN 6
J 2
(-2923 2383);
DISPLAY 0.489362 (-2923 2383);
PAINT MONO (-2923 2383);
FORCEPROP 2 LAST ROOM RISER1
J 0
(-3425 2425);
DISPLAY 0.829787 (-3425 2425);
PAINT RED (-3425 2425);
DISPLAY INVISIBLE (-3425 2425);
FORCEPROP 2 LAST BOM_COST IO_SLOT
J 0
(-3425 2475);
DISPLAY 0.829787 (-3425 2475);
DISPLAY INVISIBLE (-3425 2475);
FORCEPROP 2 LAST CDS_LIB standard
J 0
(-2925 2375);
DISPLAY INVISIBLE (-2925 2375);
FORCEPROP 1 LAST BODY_TYPE PLUMBING
J 2
(-2925 2325);
DISPLAY 0.702128 (-2925 2325);
PAINT GREEN (-2925 2325);
DISPLAY INVISIBLE (-2925 2325);
FORCEPROP 1 LAST HDL_TAP TRUE
J 2
(-3250 2250);
DISPLAY 0.702128 (-3250 2250);
PAINT GREEN (-3250 2250);
DISPLAY INVISIBLE (-3250 2250);
FORCEPROP 1 LAST PATH I494
J 2
(-2923 2375);
DISPLAY 0.872340 (-2923 2375);
PAINT GREEN (-2923 2375);
DISPLAY INVISIBLE (-2923 2375);
FORCEADD TAP..6
R 2
(-2925 2275);
FORCEPROP 3 LASTPIN (-2975 2275) SIG_NAME P5E_CPU1_G1_TX_DN<7>
J 0
(-2965 2285);
DISPLAY 0.659574 (-2965 2285);
PAINT MONO (-2965 2285);
DISPLAY INVISIBLE (-2965 2285);
FORCEPROP 1 LASTPIN (-2975 2275) BN 7
J 2
(-2923 2283);
DISPLAY 0.489362 (-2923 2283);
PAINT MONO (-2923 2283);
FORCEPROP 2 LAST ROOM RISER1
J 0
(-3425 2325);
DISPLAY 0.829787 (-3425 2325);
PAINT RED (-3425 2325);
DISPLAY INVISIBLE (-3425 2325);
FORCEPROP 2 LAST BOM_COST IO_SLOT
J 0
(-3425 2375);
DISPLAY 0.829787 (-3425 2375);
DISPLAY INVISIBLE (-3425 2375);
FORCEPROP 2 LAST CDS_LIB standard
J 0
(-2925 2275);
DISPLAY INVISIBLE (-2925 2275);
FORCEPROP 1 LAST BODY_TYPE PLUMBING
J 2
(-2925 2225);
DISPLAY 0.702128 (-2925 2225);
PAINT GREEN (-2925 2225);
DISPLAY INVISIBLE (-2925 2225);
FORCEPROP 1 LAST HDL_TAP TRUE
J 2
(-3250 2150);
DISPLAY 0.702128 (-3250 2150);
PAINT GREEN (-3250 2150);
DISPLAY INVISIBLE (-3250 2150);
FORCEPROP 1 LAST PATH I495
J 2
(-2923 2275);
DISPLAY 0.872340 (-2923 2275);
PAINT GREEN (-2923 2275);
DISPLAY INVISIBLE (-2923 2275);
FORCEADD TAP..6
R 2
(-2925 2175);
FORCEPROP 3 LASTPIN (-2975 2175) SIG_NAME P5E_CPU1_G1_TX_DN<8>
J 0
(-2965 2185);
DISPLAY 0.659574 (-2965 2185);
PAINT MONO (-2965 2185);
DISPLAY INVISIBLE (-2965 2185);
FORCEPROP 1 LASTPIN (-2975 2175) BN 8
J 2
(-2923 2183);
DISPLAY 0.489362 (-2923 2183);
PAINT MONO (-2923 2183);
FORCEPROP 2 LAST ROOM RISER1
J 0
(-3425 2225);
DISPLAY 0.829787 (-3425 2225);
PAINT RED (-3425 2225);
DISPLAY INVISIBLE (-3425 2225);
FORCEPROP 2 LAST BOM_COST IO_SLOT
J 0
(-3425 2275);
DISPLAY 0.829787 (-3425 2275);
DISPLAY INVISIBLE (-3425 2275);
FORCEPROP 2 LAST CDS_LIB standard
J 0
(-2925 2175);
DISPLAY INVISIBLE (-2925 2175);
FORCEPROP 1 LAST BODY_TYPE PLUMBING
J 2
(-2925 2125);
DISPLAY 0.702128 (-2925 2125);
PAINT GREEN (-2925 2125);
DISPLAY INVISIBLE (-2925 2125);
FORCEPROP 1 LAST HDL_TAP TRUE
J 2
(-3250 2050);
DISPLAY 0.702128 (-3250 2050);
PAINT GREEN (-3250 2050);
DISPLAY INVISIBLE (-3250 2050);
FORCEPROP 1 LAST PATH I496
J 2
(-2923 2175);
DISPLAY 0.872340 (-2923 2175);
PAINT GREEN (-2923 2175);
DISPLAY INVISIBLE (-2923 2175);
FORCEADD TAP..6
R 2
(-2925 1975);
FORCEPROP 3 LASTPIN (-2975 1975) SIG_NAME P5E_CPU1_G1_TX_DN<10>
J 0
(-2965 1985);
DISPLAY 0.659574 (-2965 1985);
PAINT MONO (-2965 1985);
DISPLAY INVISIBLE (-2965 1985);
FORCEPROP 1 LASTPIN (-2975 1975) BN 10
J 2
(-2923 1983);
DISPLAY 0.489362 (-2923 1983);
PAINT MONO (-2923 1983);
FORCEPROP 2 LAST ROOM RISER1
J 0
(-3425 2025);
DISPLAY 0.829787 (-3425 2025);
PAINT RED (-3425 2025);
DISPLAY INVISIBLE (-3425 2025);
FORCEPROP 2 LAST BOM_COST IO_SLOT
J 0
(-3425 2075);
DISPLAY 0.829787 (-3425 2075);
DISPLAY INVISIBLE (-3425 2075);
FORCEPROP 2 LAST CDS_LIB standard
J 0
(-2925 1975);
DISPLAY INVISIBLE (-2925 1975);
FORCEPROP 1 LAST BODY_TYPE PLUMBING
J 2
(-2925 1925);
DISPLAY 0.702128 (-2925 1925);
PAINT GREEN (-2925 1925);
DISPLAY INVISIBLE (-2925 1925);
FORCEPROP 1 LAST HDL_TAP TRUE
J 2
(-3250 1850);
DISPLAY 0.702128 (-3250 1850);
PAINT GREEN (-3250 1850);
DISPLAY INVISIBLE (-3250 1850);
FORCEPROP 1 LAST PATH I497
J 2
(-2923 1975);
DISPLAY 0.872340 (-2923 1975);
PAINT GREEN (-2923 1975);
DISPLAY INVISIBLE (-2923 1975);
FORCEADD TAP..6
R 2
(-2925 2075);
FORCEPROP 3 LASTPIN (-2975 2075) SIG_NAME P5E_CPU1_G1_TX_DN<9>
J 0
(-2965 2085);
DISPLAY 0.659574 (-2965 2085);
PAINT MONO (-2965 2085);
DISPLAY INVISIBLE (-2965 2085);
FORCEPROP 1 LASTPIN (-2975 2075) BN 9
J 2
(-2923 2083);
DISPLAY 0.489362 (-2923 2083);
PAINT MONO (-2923 2083);
FORCEPROP 2 LAST ROOM RISER1
J 0
(-3425 2125);
DISPLAY 0.829787 (-3425 2125);
PAINT RED (-3425 2125);
DISPLAY INVISIBLE (-3425 2125);
FORCEPROP 2 LAST BOM_COST IO_SLOT
J 0
(-3425 2175);
DISPLAY 0.829787 (-3425 2175);
DISPLAY INVISIBLE (-3425 2175);
FORCEPROP 2 LAST CDS_LIB standard
J 0
(-2925 2075);
DISPLAY INVISIBLE (-2925 2075);
FORCEPROP 1 LAST BODY_TYPE PLUMBING
J 2
(-2925 2025);
DISPLAY 0.702128 (-2925 2025);
PAINT GREEN (-2925 2025);
DISPLAY INVISIBLE (-2925 2025);
FORCEPROP 1 LAST HDL_TAP TRUE
J 2
(-3250 1950);
DISPLAY 0.702128 (-3250 1950);
PAINT GREEN (-3250 1950);
DISPLAY INVISIBLE (-3250 1950);
FORCEPROP 1 LAST PATH I498
J 2
(-2923 2075);
DISPLAY 0.872340 (-2923 2075);
PAINT GREEN (-2923 2075);
DISPLAY INVISIBLE (-2923 2075);
FORCEADD TAP..6
R 2
(-2925 1775);
FORCEPROP 3 LASTPIN (-2975 1775) SIG_NAME P5E_CPU1_G1_TX_DN<12>
J 0
(-2965 1785);
DISPLAY 0.659574 (-2965 1785);
PAINT MONO (-2965 1785);
DISPLAY INVISIBLE (-2965 1785);
FORCEPROP 1 LASTPIN (-2975 1775) BN 12
J 2
(-2923 1783);
DISPLAY 0.489362 (-2923 1783);
PAINT MONO (-2923 1783);
FORCEPROP 2 LAST ROOM RISER1
J 0
(-3425 1825);
DISPLAY 0.829787 (-3425 1825);
PAINT RED (-3425 1825);
DISPLAY INVISIBLE (-3425 1825);
FORCEPROP 2 LAST BOM_COST IO_SLOT
J 0
(-3425 1875);
DISPLAY 0.829787 (-3425 1875);
DISPLAY INVISIBLE (-3425 1875);
FORCEPROP 2 LAST CDS_LIB standard
J 0
(-2925 1775);
DISPLAY INVISIBLE (-2925 1775);
FORCEPROP 1 LAST BODY_TYPE PLUMBING
J 2
(-2925 1725);
DISPLAY 0.702128 (-2925 1725);
PAINT GREEN (-2925 1725);
DISPLAY INVISIBLE (-2925 1725);
FORCEPROP 1 LAST HDL_TAP TRUE
J 2
(-3250 1650);
DISPLAY 0.702128 (-3250 1650);
PAINT GREEN (-3250 1650);
DISPLAY INVISIBLE (-3250 1650);
FORCEPROP 1 LAST PATH I499
J 2
(-2923 1775);
DISPLAY 0.872340 (-2923 1775);
PAINT GREEN (-2923 1775);
DISPLAY INVISIBLE (-2923 1775);
FORCEADD TAP..6
R 2
(-2925 1875);
FORCEPROP 3 LASTPIN (-2975 1875) SIG_NAME P5E_CPU1_G1_TX_DN<11>
J 0
(-2965 1885);
DISPLAY 0.659574 (-2965 1885);
PAINT MONO (-2965 1885);
DISPLAY INVISIBLE (-2965 1885);
FORCEPROP 1 LASTPIN (-2975 1875) BN 11
J 2
(-2923 1883);
DISPLAY 0.489362 (-2923 1883);
PAINT MONO (-2923 1883);
FORCEPROP 2 LAST ROOM RISER1
J 0
(-3425 1925);
DISPLAY 0.829787 (-3425 1925);
PAINT RED (-3425 1925);
DISPLAY INVISIBLE (-3425 1925);
FORCEPROP 2 LAST BOM_COST IO_SLOT
J 0
(-3425 1975);
DISPLAY 0.829787 (-3425 1975);
DISPLAY INVISIBLE (-3425 1975);
FORCEPROP 2 LAST CDS_LIB standard
J 0
(-2925 1875);
DISPLAY INVISIBLE (-2925 1875);
FORCEPROP 1 LAST BODY_TYPE PLUMBING
J 2
(-2925 1825);
DISPLAY 0.702128 (-2925 1825);
PAINT GREEN (-2925 1825);
DISPLAY INVISIBLE (-2925 1825);
FORCEPROP 1 LAST HDL_TAP TRUE
J 2
(-3250 1750);
DISPLAY 0.702128 (-3250 1750);
PAINT GREEN (-3250 1750);
DISPLAY INVISIBLE (-3250 1750);
FORCEPROP 1 LAST PATH I500
J 2
(-2923 1875);
DISPLAY 0.872340 (-2923 1875);
PAINT GREEN (-2923 1875);
DISPLAY INVISIBLE (-2923 1875);
FORCEADD TAP..6
R 2
(-2925 1675);
FORCEPROP 3 LASTPIN (-2975 1675) SIG_NAME P5E_CPU1_G1_TX_DN<13>
J 0
(-2965 1685);
DISPLAY 0.659574 (-2965 1685);
PAINT MONO (-2965 1685);
DISPLAY INVISIBLE (-2965 1685);
FORCEPROP 1 LASTPIN (-2975 1675) BN 13
J 2
(-2923 1683);
DISPLAY 0.489362 (-2923 1683);
PAINT MONO (-2923 1683);
FORCEPROP 2 LAST ROOM RISER1
J 0
(-3425 1725);
DISPLAY 0.829787 (-3425 1725);
PAINT RED (-3425 1725);
DISPLAY INVISIBLE (-3425 1725);
FORCEPROP 2 LAST BOM_COST IO_SLOT
J 0
(-3425 1775);
DISPLAY 0.829787 (-3425 1775);
DISPLAY INVISIBLE (-3425 1775);
FORCEPROP 2 LAST CDS_LIB standard
J 0
(-2925 1675);
DISPLAY INVISIBLE (-2925 1675);
FORCEPROP 1 LAST BODY_TYPE PLUMBING
J 2
(-2925 1625);
DISPLAY 0.702128 (-2925 1625);
PAINT GREEN (-2925 1625);
DISPLAY INVISIBLE (-2925 1625);
FORCEPROP 1 LAST HDL_TAP TRUE
J 2
(-3250 1550);
DISPLAY 0.702128 (-3250 1550);
PAINT GREEN (-3250 1550);
DISPLAY INVISIBLE (-3250 1550);
FORCEPROP 1 LAST PATH I501
J 2
(-2923 1675);
DISPLAY 0.872340 (-2923 1675);
PAINT GREEN (-2923 1675);
DISPLAY INVISIBLE (-2923 1675);
FORCEADD TAP..6
R 2
(-2925 1575);
FORCEPROP 3 LASTPIN (-2975 1575) SIG_NAME P5E_CPU1_G1_TX_DN<14>
J 0
(-2965 1585);
DISPLAY 0.659574 (-2965 1585);
PAINT MONO (-2965 1585);
DISPLAY INVISIBLE (-2965 1585);
FORCEPROP 1 LASTPIN (-2975 1575) BN 14
J 2
(-2923 1583);
DISPLAY 0.489362 (-2923 1583);
PAINT MONO (-2923 1583);
FORCEPROP 2 LAST ROOM RISER1
J 0
(-3425 1625);
DISPLAY 0.829787 (-3425 1625);
PAINT RED (-3425 1625);
DISPLAY INVISIBLE (-3425 1625);
FORCEPROP 2 LAST CDS_LIB standard
J 0
(-2925 1575);
DISPLAY INVISIBLE (-2925 1575);
FORCEPROP 2 LAST BOM_COST IO_SLOT
J 0
(-3425 1675);
DISPLAY 0.829787 (-3425 1675);
DISPLAY INVISIBLE (-3425 1675);
FORCEPROP 1 LAST BODY_TYPE PLUMBING
J 2
(-2925 1525);
DISPLAY 0.702128 (-2925 1525);
PAINT GREEN (-2925 1525);
DISPLAY INVISIBLE (-2925 1525);
FORCEPROP 1 LAST HDL_TAP TRUE
J 2
(-3250 1450);
DISPLAY 0.702128 (-3250 1450);
PAINT GREEN (-3250 1450);
DISPLAY INVISIBLE (-3250 1450);
FORCEPROP 1 LAST PATH I502
J 2
(-2923 1575);
DISPLAY 0.872340 (-2923 1575);
PAINT GREEN (-2923 1575);
DISPLAY INVISIBLE (-2923 1575);
FORCEADD TAP..6
R 2
(-2925 1475);
FORCEPROP 3 LASTPIN (-2975 1475) SIG_NAME P5E_CPU1_G1_TX_DN<15>
J 0
(-2965 1485);
DISPLAY 0.659574 (-2965 1485);
PAINT MONO (-2965 1485);
DISPLAY INVISIBLE (-2965 1485);
FORCEPROP 1 LASTPIN (-2975 1475) BN 15
J 2
(-2923 1483);
DISPLAY 0.489362 (-2923 1483);
PAINT MONO (-2923 1483);
FORCEPROP 2 LAST ROOM RISER1
J 0
(-3425 1525);
DISPLAY 0.829787 (-3425 1525);
PAINT RED (-3425 1525);
DISPLAY INVISIBLE (-3425 1525);
FORCEPROP 2 LAST BOM_COST IO_SLOT
J 0
(-3425 1575);
DISPLAY 0.829787 (-3425 1575);
DISPLAY INVISIBLE (-3425 1575);
FORCEPROP 2 LAST CDS_LIB standard
J 0
(-2925 1475);
DISPLAY INVISIBLE (-2925 1475);
FORCEPROP 1 LAST BODY_TYPE PLUMBING
J 2
(-2925 1425);
DISPLAY 0.702128 (-2925 1425);
PAINT GREEN (-2925 1425);
DISPLAY INVISIBLE (-2925 1425);
FORCEPROP 1 LAST HDL_TAP TRUE
J 2
(-3250 1350);
DISPLAY 0.702128 (-3250 1350);
PAINT GREEN (-3250 1350);
DISPLAY INVISIBLE (-3250 1350);
FORCEPROP 1 LAST PATH I503
J 2
(-2923 1475);
DISPLAY 0.872340 (-2923 1475);
PAINT GREEN (-2923 1475);
DISPLAY INVISIBLE (-2923 1475);
FORCEADD QUANTA_TITLE_BLOCK_C..1
(-100 100);
FORCEPROP 0 LAST CDS_CON_LAST_MODIFIED Thu Sep 14 16:11:58 2023
J 0
(-1985 115);
DISPLAY INVISIBLE (-1985 115);
FORCEPROP 1 LAST CUSTOM_TXT_CDS <CON_LAST_MODIFIED>
J 0
(-1985 115);
DISPLAY 0.978723 (-1985 115);
FORCEPROP 2 LAST CUSTOM_TXT_CDS <XR_PAGE_TITLE>
J 0
(-7990 5350);
DISPLAY 0.638298 (-7990 5350);
PAINT PINK (-7990 5350);
DISPLAY INVISIBLE (-7990 5350);
FORCEPROP 1 LAST CUSTOM_TXT_CDS <NAME_2>
J 0
(-3275 150);
FORCEPROP 1 LAST CUSTOM_TXT_CDS <NAME_1>
J 0
(-3275 275);
FORCEPROP 1 LAST CUSTOM_TXT_CDS <Q_NUMBER>
J 0
(-1503 203);
DISPLAY 1.212766 (-1503 203);
FORCEPROP 1 LAST CUSTOM_TXT_CDS <Q_PROJ>
J 0
(-2482 202);
DISPLAY 1.212766 (-2482 202);
FORCEPROP 1 LAST CUSTOM_TXT_CDS <Q_REV>
J 0
(-284 203);
DISPLAY 1.212766 (-284 203);
FORCEPROP 1 LAST CUSTOM_TXT_CDS <CON_PAGE_NUM> OF <CON_TOTAL_PAGES>
J 0
(-546 118);
DISPLAY 0.978723 (-546 118);
FORCEPROP 1 LAST Q_TITLE CPU1 PCIE G0/G1
J 0
(-9375 175);
DISPLAY 2.446809 (-9375 175);
PAINT GREEN (-9375 175);
FORCEPROP 2 LAST CDS_LIB pure_quanta
J 0
(-100 100);
DISPLAY INVISIBLE (-100 100);
FORCEPROP 1 LAST CDS_LMAN_SYM_OUTLINE -9475,6775,100,-125
J 0
(-100 100);
DISPLAY 0.468085 (-100 100);
PAINT GREEN (-100 100);
DISPLAY INVISIBLE (-100 100);
FORCEPROP 2 LAST PAGE_BORDER TRUE
J 0
(-7990 5350);
DISPLAY 0.638298 (-7990 5350);
PAINT PINK (-7990 5350);
DISPLAY INVISIBLE (-7990 5350);
FORCEPROP 2 LAST CDS_XR_PAGE_TITLE CR-49 : @T6G_MB_LIB.T6G(SCH_1):PAGE49
J 0
(-7990 5350);
DISPLAY 0.638298 (-7990 5350);
PAINT PINK (-7990 5350);
DISPLAY INVISIBLE (-7990 5350);
FORCEPROP 1 LAST Q_DEPT BU9
J 1
(-3863 149);
DISPLAY 1.957447 (-3863 149);
PAINT GREEN (-3863 149);
DISPLAY INVISIBLE (-3863 149);
FORCEPROP 1 LAST COMMENT_BODY TRUE
J 0
(-88 87);
DISPLAY 0.978723 (-88 87);
PAINT GREEN (-88 87);
DISPLAY INVISIBLE (-88 87);
WIRE 17 -1 (-6575 4275)(-6575 4375);
WIRE 17 -1 (-6575 4375)(-6575 4475);
WIRE 17 -1 (-6575 4475)(-6575 4575);
WIRE 17 -1 (-6575 4575)(-6575 4675);
WIRE 17 -1 (-6575 4675)(-6575 4775);
WIRE 17 -1 (-6575 4775)(-6575 4875);
WIRE 17 -1 (-6575 4875)(-6575 4975);
WIRE 17 -1 (-6575 4975)(-6575 5075);
WIRE 17 -1 (-6575 5075)(-6575 5175);
WIRE 17 -1 (-6575 5175)(-6575 5275);
WIRE 17 -1 (-6575 5275)(-6575 5375);
WIRE 17 -1 (-6575 5375)(-6575 5475);
WIRE 17 -1 (-6575 5475)(-6575 5575);
WIRE 17 -1 (-6575 5575)(-6575 5675);
WIRE 17 -1 (-6575 5675)(-6575 5775);
WIRE 17 -1 (-6575 5775)(-6575 5975);
WIRE 17 -1 (-6575 5975)(-7675 5975);
FORCEPROP 2 LAST SIG_NAME GMI_CPU0_G2_CPU1_G0_TX_DP<0:15>
J 0
(-7685 5985);
DISPLAY 0.489362 (-7685 5985);
WIRE 17 -1 (-6725 4325)(-6725 4425);
WIRE 17 -1 (-6725 4225)(-6725 4325);
WIRE 17 -1 (-6725 4425)(-6725 4525);
WIRE 17 -1 (-6725 4525)(-6725 4625);
WIRE 17 -1 (-6725 4625)(-6725 4725);
WIRE 17 -1 (-6725 4725)(-6725 4825);
WIRE 17 -1 (-6725 4825)(-6725 4925);
WIRE 17 -1 (-6725 4925)(-6725 5025);
WIRE 17 -1 (-6725 5025)(-6725 5125);
WIRE 17 -1 (-6725 5125)(-6725 5225);
WIRE 17 -1 (-6725 5225)(-6725 5325);
WIRE 17 -1 (-6725 5325)(-6725 5425);
WIRE 17 -1 (-6725 5425)(-6725 5525);
WIRE 17 -1 (-6725 5525)(-6725 5625);
WIRE 17 -1 (-6725 5625)(-6725 5725);
WIRE 17 -1 (-6725 5725)(-6725 5925);
WIRE 17 -1 (-6725 5925)(-7675 5925);
WIRE 17 -1 (-3025 1650)(-3025 1550);
WIRE 17 -1 (-3025 1750)(-3025 1650);
WIRE 17 -1 (-3025 1850)(-3025 1750);
WIRE 17 -1 (-3025 1950)(-3025 1850);
WIRE 17 -1 (-3025 2050)(-3025 1950);
WIRE 17 -1 (-3025 2150)(-3025 2050);
WIRE 17 -1 (-3025 2250)(-3025 2150);
WIRE 17 -1 (-3025 2350)(-3025 2250);
WIRE 17 -1 (-3025 2450)(-3025 2350);
WIRE 17 -1 (-3025 2550)(-3025 2450);
WIRE 17 -1 (-3025 2650)(-3025 2550);
WIRE 17 -1 (-3025 2750)(-3025 2650);
WIRE 17 -1 (-3025 2850)(-3025 2750);
WIRE 17 -1 (-3025 2950)(-3025 2850);
WIRE 17 -1 (-3025 3050)(-3025 2950);
WIRE 17 -1 (-3025 3250)(-3025 3050);
WIRE 17 -1 (-3025 3250)(-1850 3250);
FORCEPROP 2 LAST SIG_NAME P5E_CPU1_G1_TX_DP<15:0>
J 0
(-2835 3285);
DISPLAY 0.489362 (-2835 3285);
WIRE 17 -1 (-2875 2100)(-2875 2000);
WIRE 17 -1 (-2875 2200)(-2875 2100);
WIRE 17 -1 (-2875 2000)(-2875 1900);
WIRE 17 -1 (-2875 1900)(-2875 1800);
WIRE 17 -1 (-2875 2300)(-2875 2200);
WIRE 17 -1 (-2875 2400)(-2875 2300);
WIRE 17 -1 (-2875 1800)(-2875 1700);
WIRE 17 -1 (-2875 1700)(-2875 1600);
WIRE 17 -1 (-2875 2500)(-2875 2400);
WIRE 17 -1 (-2875 2600)(-2875 2500);
WIRE 17 -1 (-2875 1600)(-2875 1500);
WIRE 17 -1 (-2875 2700)(-2875 2600);
WIRE 17 -1 (-2875 2800)(-2875 2700);
WIRE 17 -1 (-2875 2900)(-2875 2800);
WIRE 17 -1 (-2875 3000)(-2875 2900);
WIRE 17 -1 (-2875 3200)(-2875 3000);
WIRE 17 -1 (-2875 3200)(-1850 3200);
FORCEPROP 2 LAST SIG_NAME P5E_CPU1_G1_TX_DN<15:0>
J 0
(-2835 3210);
DISPLAY 0.489362 (-2835 3210);
WIRE 17 -1 (-3050 4575)(-3050 4475);
WIRE 17 -1 (-3050 4675)(-3050 4575);
WIRE 17 -1 (-3050 4475)(-3050 4375);
WIRE 17 -1 (-3050 4375)(-3050 4275);
WIRE 17 -1 (-3050 4775)(-3050 4675);
WIRE 17 -1 (-3050 4875)(-3050 4775);
WIRE 17 -1 (-3050 4975)(-3050 4875);
WIRE 17 -1 (-3050 5075)(-3050 4975);
WIRE 17 -1 (-3050 5175)(-3050 5075);
WIRE 17 -1 (-3050 5275)(-3050 5175);
WIRE 17 -1 (-3050 5375)(-3050 5275);
WIRE 17 -1 (-3050 5475)(-3050 5375);
WIRE 17 -1 (-3050 5575)(-3050 5475);
WIRE 17 -1 (-3050 5675)(-3050 5575);
WIRE 17 -1 (-3050 5775)(-3050 5675);
WIRE 17 -1 (-3050 5975)(-3050 5775);
WIRE 17 -1 (-3050 5975)(-1875 5975);
FORCEPROP 2 LAST SIG_NAME GMI_CPU1_G0_CPU0_G2_TX_DP<0:15>
J 0
(-2860 5985);
DISPLAY 0.489362 (-2860 5985);
WIRE 17 -1 (-2900 4825)(-2900 4725);
WIRE 17 -1 (-2900 4925)(-2900 4825);
WIRE 17 -1 (-2900 4725)(-2900 4625);
WIRE 17 -1 (-2900 4625)(-2900 4525);
WIRE 17 -1 (-2900 5025)(-2900 4925);
WIRE 17 -1 (-2900 5125)(-2900 5025);
WIRE 17 -1 (-2900 4525)(-2900 4425);
WIRE 17 -1 (-2900 4425)(-2900 4325);
WIRE 17 -1 (-2900 5225)(-2900 5125);
WIRE 17 -1 (-2900 5325)(-2900 5225);
WIRE 17 -1 (-2900 4325)(-2900 4225);
WIRE 17 -1 (-2900 5425)(-2900 5325);
WIRE 17 -1 (-2900 5525)(-2900 5425);
WIRE 17 -1 (-2900 5625)(-2900 5525);
WIRE 17 -1 (-2900 5725)(-2900 5625);
WIRE 17 -1 (-2900 5925)(-2900 5725);
WIRE 17 -1 (-2900 5925)(-1875 5925);
FORCEPROP 2 LAST SIG_NAME GMI_CPU1_G0_CPU0_G2_TX_DN<0:15>
J 0
(-2860 5935);
DISPLAY 0.489362 (-2860 5935);
WIRE 17 -1 (-6700 1500)(-6700 1600);
WIRE 17 -1 (-6700 1600)(-6700 1700);
WIRE 17 -1 (-6700 1700)(-6700 1800);
WIRE 17 -1 (-6700 1800)(-6700 1900);
WIRE 17 -1 (-6700 1900)(-6700 2000);
WIRE 17 -1 (-6700 2000)(-6700 2100);
WIRE 17 -1 (-6700 2100)(-6700 2200);
WIRE 17 -1 (-6700 2200)(-6700 2300);
WIRE 17 -1 (-6700 2300)(-6700 2400);
WIRE 17 -1 (-6700 2400)(-6700 2500);
WIRE 17 -1 (-6700 2500)(-6700 2600);
WIRE 17 -1 (-6700 2600)(-6700 2700);
WIRE 17 -1 (-6700 2700)(-6700 2800);
WIRE 17 -1 (-6700 2800)(-6700 2900);
WIRE 17 -1 (-6700 2900)(-6700 3000);
WIRE 17 -1 (-6700 3000)(-6700 3200);
WIRE 17 -1 (-6700 3200)(-7550 3200);
FORCEPROP 2 LAST SIG_NAME P5E_CPU1_G1_RX_DN<15:0>
J 0
(-7560 3210);
DISPLAY 0.489362 (-7560 3210);
WIRE 17 -1 (-6550 1550)(-6550 1650);
WIRE 17 -1 (-6550 1650)(-6550 1750);
WIRE 17 -1 (-6550 1750)(-6550 1850);
WIRE 17 -1 (-6550 1850)(-6550 1950);
WIRE 17 -1 (-6550 1950)(-6550 2050);
WIRE 17 -1 (-6550 2050)(-6550 2150);
WIRE 17 -1 (-6550 2150)(-6550 2250);
WIRE 17 -1 (-6550 2250)(-6550 2350);
WIRE 17 -1 (-6550 2350)(-6550 2450);
WIRE 17 -1 (-6550 2450)(-6550 2550);
WIRE 17 -1 (-6550 2550)(-6550 2650);
WIRE 17 -1 (-6550 2650)(-6550 2750);
WIRE 17 -1 (-6550 2750)(-6550 2850);
WIRE 17 -1 (-6550 2850)(-6550 2950);
WIRE 17 -1 (-6550 2950)(-6550 3050);
WIRE 17 -1 (-6550 3050)(-6550 3250);
WIRE 17 -1 (-6550 3250)(-7550 3250);
WIRE 16 -1 (-3500 2625)(-3125 2625);
WIRE 16 -1 (-3500 2575)(-2975 2575);
WIRE 16 -1 (-3500 2825)(-3125 2825);
WIRE 16 -1 (-3500 2775)(-2975 2775);
WIRE 16 -1 (-3500 2175)(-2975 2175);
WIRE 16 -1 (-3500 2225)(-3125 2225);
WIRE 16 -1 (-6450 3025)(-6000 3025);
WIRE 16 -1 (-6450 2425)(-6000 2425);
WIRE 16 -1 (-6600 2375)(-6000 2375);
WIRE 16 -1 (-6450 2325)(-6000 2325);
WIRE 16 -1 (-6600 1675)(-6000 1675);
WIRE 16 -1 (-6600 2275)(-6000 2275);
WIRE 16 -1 (-6600 2175)(-6000 2175);
WIRE 16 -1 (-6600 2575)(-6000 2575);
WIRE 16 -1 (-6450 2625)(-6000 2625);
WIRE 16 -1 (-6600 2675)(-6000 2675);
WIRE 16 -1 (-3500 2875)(-2975 2875);
WIRE 16 -1 (-3500 2925)(-3125 2925);
WIRE 16 -1 (-3500 2675)(-2975 2675);
WIRE 16 -1 (-3500 2125)(-3125 2125);
WIRE 16 -1 (-3500 2275)(-2975 2275);
WIRE 16 -1 (-3500 2325)(-3125 2325);
WIRE 16 -1 (-3500 2375)(-2975 2375);
WIRE 16 -1 (-3500 2425)(-3125 2425);
WIRE 16 -1 (-3500 2475)(-2975 2475);
WIRE 16 -1 (-3500 2975)(-2975 2975);
WIRE 16 -1 (-3500 3025)(-3125 3025);
WIRE 16 -1 (-3500 2725)(-3125 2725);
WIRE 16 -1 (-3500 2525)(-3125 2525);
WIRE 16 -1 (-6450 2525)(-6000 2525);
WIRE 16 -1 (-6450 2225)(-6000 2225);
WIRE 16 -1 (-6600 2475)(-6000 2475);
WIRE 16 -1 (-6450 2725)(-6000 2725);
WIRE 16 -1 (-6600 2775)(-6000 2775);
WIRE 16 -1 (-6450 2825)(-6000 2825);
WIRE 16 -1 (-6600 2875)(-6000 2875);
WIRE 16 -1 (-6450 2925)(-6000 2925);
WIRE 16 -1 (-6600 2975)(-6000 2975);
WIRE 16 -1 (-6600 1575)(-6000 1575);
WIRE 16 -1 (-6600 1775)(-6000 1775);
WIRE 16 -1 (-6600 1875)(-6000 1875);
WIRE 16 -1 (-6600 1975)(-6000 1975);
WIRE 16 -1 (-6600 2075)(-6000 2075);
WIRE 16 -1 (-6450 1625)(-6000 1625);
WIRE 16 -1 (-6450 1725)(-6000 1725);
WIRE 16 -1 (-6450 1825)(-6000 1825);
WIRE 16 -1 (-6450 1925)(-6000 1925);
WIRE 16 -1 (-6450 2025)(-6000 2025);
WIRE 16 -1 (-6450 2125)(-6000 2125);
WIRE 16 -1 (-6450 1525)(-6000 1525);
WIRE 16 -1 (-6600 1475)(-6000 1475);
WIRE 16 -1 (-3525 4200)(-3000 4200);
WIRE 16 -1 (-3525 4250)(-3150 4250);
WIRE 16 -1 (-3525 4300)(-3000 4300);
WIRE 16 -1 (-3525 4350)(-3150 4350);
WIRE 16 -1 (-3525 4400)(-3000 4400);
WIRE 16 -1 (-3525 4500)(-3000 4500);
WIRE 16 -1 (-3525 4600)(-3000 4600);
WIRE 16 -1 (-3525 4750)(-3150 4750);
WIRE 16 -1 (-3525 4800)(-3000 4800);
WIRE 16 -1 (-3525 4900)(-3000 4900);
WIRE 16 -1 (-3525 5400)(-3000 5400);
WIRE 16 -1 (-3525 5500)(-3000 5500);
WIRE 16 -1 (-3525 5750)(-3150 5750);
WIRE 16 -1 (-3525 5600)(-3000 5600);
WIRE 16 -1 (-3525 5650)(-3150 5650);
WIRE 16 -1 (-6625 5700)(-6025 5700);
WIRE 16 -1 (-6475 5750)(-6025 5750);
WIRE 16 -1 (-6625 4200)(-6025 4200);
WIRE 16 -1 (-3525 5700)(-3000 5700);
WIRE 16 -1 (-3525 5300)(-3000 5300);
WIRE 16 -1 (-3525 5200)(-3000 5200);
WIRE 16 -1 (-3525 5100)(-3000 5100);
WIRE 16 -1 (-3525 5000)(-3000 5000);
WIRE 16 -1 (-3525 4700)(-3000 4700);
WIRE 16 -1 (-3525 5550)(-3150 5550);
WIRE 16 -1 (-3525 5450)(-3150 5450);
WIRE 16 -1 (-3525 5350)(-3150 5350);
WIRE 16 -1 (-3525 5250)(-3150 5250);
WIRE 16 -1 (-3525 5150)(-3150 5150);
WIRE 16 -1 (-3525 5050)(-3150 5050);
WIRE 16 -1 (-3525 4950)(-3150 4950);
WIRE 16 -1 (-3525 4850)(-3150 4850);
WIRE 16 -1 (-3525 4650)(-3150 4650);
WIRE 16 -1 (-3525 4550)(-3150 4550);
WIRE 16 -1 (-3525 4450)(-3150 4450);
WIRE 16 -1 (-3500 2075)(-2975 2075);
WIRE 16 -1 (-3500 1475)(-2975 1475);
WIRE 16 -1 (-3500 1575)(-2975 1575);
WIRE 16 -1 (-3500 1675)(-2975 1675);
WIRE 16 -1 (-3500 1775)(-2975 1775);
WIRE 16 -1 (-3500 1875)(-2975 1875);
WIRE 16 -1 (-3500 1975)(-2975 1975);
WIRE 16 -1 (-3500 1625)(-3125 1625);
WIRE 16 -1 (-3500 1725)(-3125 1725);
WIRE 16 -1 (-3500 1825)(-3125 1825);
WIRE 16 -1 (-3500 1925)(-3125 1925);
WIRE 16 -1 (-3500 2025)(-3125 2025);
WIRE 16 -1 (-3500 1525)(-3125 1525);
WIRE 16 -1 (-6625 5600)(-6025 5600);
WIRE 16 -1 (-6625 5500)(-6025 5500);
WIRE 16 -1 (-6625 5400)(-6025 5400);
WIRE 16 -1 (-6625 5300)(-6025 5300);
WIRE 16 -1 (-6625 5200)(-6025 5200);
WIRE 16 -1 (-6625 5100)(-6025 5100);
WIRE 16 -1 (-6625 5000)(-6025 5000);
WIRE 16 -1 (-6625 4900)(-6025 4900);
WIRE 16 -1 (-6625 4800)(-6025 4800);
WIRE 16 -1 (-6625 4700)(-6025 4700);
WIRE 16 -1 (-6625 4600)(-6025 4600);
WIRE 16 -1 (-6625 4500)(-6025 4500);
WIRE 16 -1 (-6625 4400)(-6025 4400);
WIRE 16 -1 (-6625 4300)(-6025 4300);
WIRE 16 -1 (-6475 5650)(-6025 5650);
WIRE 16 -1 (-6475 5550)(-6025 5550);
WIRE 16 -1 (-6475 5450)(-6025 5450);
WIRE 16 -1 (-6475 5350)(-6025 5350);
WIRE 16 -1 (-6475 5250)(-6025 5250);
WIRE 16 -1 (-6475 5150)(-6025 5150);
WIRE 16 -1 (-6475 5050)(-6025 5050);
WIRE 16 -1 (-6475 4950)(-6025 4950);
WIRE 16 -1 (-6475 4850)(-6025 4850);
WIRE 16 -1 (-6475 4750)(-6025 4750);
WIRE 16 -1 (-6475 4650)(-6025 4650);
WIRE 16 -1 (-6475 4550)(-6025 4550);
WIRE 16 -1 (-6475 4450)(-6025 4450);
WIRE 16 -1 (-6475 4350)(-6025 4350);
WIRE 16 -1 (-6475 4250)(-6025 4250);
FORCENOTE
CPU1 G1[15:0] TO OCP SLOT#1
(-2400 2225) 0;
DISPLAY LEFT (-2400 2225);
DISPLAY 1.595745 (-2400 2225);
FORCENOTE
LANE REVERSAL
(-2050 4775) 0;
DISPLAY LEFT (-2050 4775);
DISPLAY 1.595745 (-2050 4775);
QUIT
